(kicad_sch
	(version 20250114)
	(generator "eeschema")
	(generator_version "9.0")
	(paper "A3")
	(title_block
		(title "RDIMM DDR5 Tester")
		(date "2026-05-21")
		(rev "2.2.0")
		(company "Antmicro")
		(comment 1 "www.antmicro.com")
		(comment 2 "Antmicro")
	)
	(text "Place capacitors close to connector"
		(exclude_from_sim no)
		(at 120.65 67.31 0)
		(effects
			(font
				(size 1.27 1.27)
			)
			(justify left bottom)
		)
	)
	(text "Rate set to MM for\nthird overtone 144.285 MHz\ncrystal"
		(exclude_from_sim no)
		(at 332.74 214.63 0)
		(effects
			(font
				(size 1.27 1.27)
			)
			(justify left bottom)
		)
	)
	(text "I2C: 0x68"
		(exclude_from_sim no)
		(at 317.5 240.03 0)
		(effects
			(font
				(size 1.27 1.27)
			)
			(justify left bottom)
		)
	)
	(text "PCIe 3.0 x8"
		(exclude_from_sim no)
		(at 15.24 24.13 0)
		(effects
			(font
				(size 2 2)
				(thickness 0.4)
				(bold yes)
			)
			(justify left bottom)
		)
	)
	(text "MGT Interface"
		(exclude_from_sim no)
		(at 14.605 19.05 0)
		(effects
			(font
				(size 3 3)
				(thickness 0.6)
				(bold yes)
			)
			(justify left bottom)
		)
	)
	(text "HDMI"
		(exclude_from_sim no)
		(at 213.36 19.05 0)
		(effects
			(font
				(size 2 2)
				(thickness 0.4)
				(bold yes)
			)
			(justify left bottom)
		)
	)
	(text "Clock multipler"
		(exclude_from_sim no)
		(at 213.36 147.32 0)
		(effects
			(font
				(size 2 2)
				(thickness 0.4)
				(bold yes)
			)
			(justify left bottom)
		)
	)
	(junction
		(at 308.61 227.33)
		(diameter 0)
		(color 0 0 0 0)
	)
	(junction
		(at 300.99 181.61)
		(diameter 0)
		(color 0 0 0 0)
	)
	(junction
		(at 308.61 224.79)
		(diameter 0)
		(color 0 0 0 0)
	)
	(junction
		(at 223.52 167.64)
		(diameter 0)
		(color 0 0 0 0)
	)
	(junction
		(at 308.61 234.95)
		(diameter 0)
		(color 0 0 0 0)
	)
	(junction
		(at 308.61 229.87)
		(diameter 0)
		(color 0 0 0 0)
	)
	(junction
		(at 309.88 173.99)
		(diameter 0)
		(color 0 0 0 0)
	)
	(junction
		(at 270.51 204.47)
		(diameter 0)
		(color 0 0 0 0)
	)
	(junction
		(at 270.51 196.85)
		(diameter 0)
		(color 0 0 0 0)
	)
	(junction
		(at 228.6 167.64)
		(diameter 0)
		(color 0 0 0 0)
	)
	(junction
		(at 233.68 167.64)
		(diameter 0)
		(color 0 0 0 0)
	)
	(no_connect
		(at 76.2 128.27)
	)
	(no_connect
		(at 76.2 200.66)
	)
	(no_connect
		(at 278.13 104.14)
	)
	(no_connect
		(at 76.2 203.2)
	)
	(no_connect
		(at 278.13 101.6)
	)
	(no_connect
		(at 311.15 214.63)
	)
	(no_connect
		(at 76.2 208.28)
	)
	(no_connect
		(at 76.2 205.74)
	)
	(no_connect
		(at 76.2 130.81)
	)
	(bus_entry
		(at 358.14 86.36)
		(size 2.54 2.54)
		(stroke
			(width 0)
			(type default)
		)
	)
	(bus_entry
		(at 289.56 214.63)
		(size 2.54 2.54)
		(stroke
			(width 0)
			(type default)
		)
	)
	(bus_entry
		(at 358.14 119.38)
		(size 2.54 2.54)
		(stroke
			(width 0)
			(type default)
		)
	)
	(bus_entry
		(at 163.83 104.14)
		(size 2.54 -2.54)
		(stroke
			(width 0)
			(type default)
		)
	)
	(bus_entry
		(at 163.83 115.57)
		(size 2.54 -2.54)
		(stroke
			(width 0)
			(type default)
		)
	)
	(bus_entry
		(at 163.83 160.02)
		(size 2.54 -2.54)
		(stroke
			(width 0)
			(type default)
		)
	)
	(bus_entry
		(at 163.83 125.73)
		(size 2.54 -2.54)
		(stroke
			(width 0)
			(type default)
		)
	)
	(bus_entry
		(at 163.83 77.47)
		(size 2.54 -2.54)
		(stroke
			(width 0)
			(type default)
		)
	)
	(bus_entry
		(at 163.83 157.48)
		(size 2.54 -2.54)
		(stroke
			(width 0)
			(type default)
		)
	)
	(bus_entry
		(at 358.14 57.15)
		(size 2.54 -2.54)
		(stroke
			(width 0)
			(type default)
		)
	)
	(bus_entry
		(at 163.83 199.39)
		(size 2.54 -2.54)
		(stroke
			(width 0)
			(type default)
		)
	)
	(bus_entry
		(at 163.83 151.13)
		(size 2.54 -2.54)
		(stroke
			(width 0)
			(type default)
		)
	)
	(bus_entry
		(at 358.14 62.23)
		(size 2.54 -2.54)
		(stroke
			(width 0)
			(type default)
		)
	)
	(bus_entry
		(at 163.83 170.18)
		(size 2.54 -2.54)
		(stroke
			(width 0)
			(type default)
		)
	)
	(bus_entry
		(at 163.83 137.16)
		(size 2.54 -2.54)
		(stroke
			(width 0)
			(type default)
		)
	)
	(bus_entry
		(at 163.83 153.67)
		(size 2.54 -2.54)
		(stroke
			(width 0)
			(type default)
		)
	)
	(bus_entry
		(at 358.14 81.28)
		(size 2.54 -2.54)
		(stroke
			(width 0)
			(type default)
		)
	)
	(bus_entry
		(at 289.56 217.17)
		(size 2.54 2.54)
		(stroke
			(width 0)
			(type default)
		)
	)
	(bus_entry
		(at 358.14 69.85)
		(size 2.54 -2.54)
		(stroke
			(width 0)
			(type default)
		)
	)
	(bus_entry
		(at 358.14 78.74)
		(size 2.54 -2.54)
		(stroke
			(width 0)
			(type default)
		)
	)
	(bus_entry
		(at 358.14 97.79)
		(size 2.54 2.54)
		(stroke
			(width 0)
			(type default)
		)
	)
	(bus_entry
		(at 163.83 106.68)
		(size 2.54 -2.54)
		(stroke
			(width 0)
			(type default)
		)
	)
	(bus_entry
		(at 358.14 106.68)
		(size 2.54 2.54)
		(stroke
			(width 0)
			(type default)
		)
	)
	(bus_entry
		(at 163.83 134.62)
		(size 2.54 -2.54)
		(stroke
			(width 0)
			(type default)
		)
	)
	(bus_entry
		(at 163.83 208.28)
		(size 2.54 -2.54)
		(stroke
			(width 0)
			(type default)
		)
	)
	(bus_entry
		(at 163.83 95.25)
		(size 2.54 -2.54)
		(stroke
			(width 0)
			(type default)
		)
	)
	(bus_entry
		(at 163.83 87.63)
		(size 2.54 -2.54)
		(stroke
			(width 0)
			(type default)
		)
	)
	(bus_entry
		(at 163.83 147.32)
		(size 2.54 -2.54)
		(stroke
			(width 0)
			(type default)
		)
	)
	(bus_entry
		(at 163.83 97.79)
		(size 2.54 -2.54)
		(stroke
			(width 0)
			(type default)
		)
	)
	(bus_entry
		(at 163.83 74.93)
		(size 2.54 -2.54)
		(stroke
			(width 0)
			(type default)
		)
	)
	(bus_entry
		(at 358.14 64.77)
		(size 2.54 -2.54)
		(stroke
			(width 0)
			(type default)
		)
	)
	(bus_entry
		(at 163.83 186.69)
		(size 2.54 -2.54)
		(stroke
			(width 0)
			(type default)
		)
	)
	(bus_entry
		(at 163.83 184.15)
		(size 2.54 -2.54)
		(stroke
			(width 0)
			(type default)
		)
	)
	(bus_entry
		(at 163.83 85.09)
		(size 2.54 -2.54)
		(stroke
			(width 0)
			(type default)
		)
	)
	(bus_entry
		(at 163.83 128.27)
		(size 2.54 -2.54)
		(stroke
			(width 0)
			(type default)
		)
	)
	(bus_entry
		(at 358.14 72.39)
		(size 2.54 -2.54)
		(stroke
			(width 0)
			(type default)
		)
	)
	(bus_entry
		(at 358.14 121.92)
		(size 2.54 2.54)
		(stroke
			(width 0)
			(type default)
		)
	)
	(bus_entry
		(at 163.83 118.11)
		(size 2.54 -2.54)
		(stroke
			(width 0)
			(type default)
		)
	)
	(bus_entry
		(at 358.14 88.9)
		(size 2.54 2.54)
		(stroke
			(width 0)
			(type default)
		)
	)
	(bus_entry
		(at 358.14 54.61)
		(size 2.54 -2.54)
		(stroke
			(width 0)
			(type default)
		)
	)
	(bus_entry
		(at 358.14 95.25)
		(size 2.54 2.54)
		(stroke
			(width 0)
			(type default)
		)
	)
	(bus_entry
		(at 163.83 177.8)
		(size 2.54 -2.54)
		(stroke
			(width 0)
			(type default)
		)
	)
	(bus_entry
		(at 163.83 193.04)
		(size 2.54 -2.54)
		(stroke
			(width 0)
			(type default)
		)
	)
	(bus_entry
		(at 163.83 166.37)
		(size 2.54 -2.54)
		(stroke
			(width 0)
			(type default)
		)
	)
	(bus_entry
		(at 163.83 163.83)
		(size 2.54 -2.54)
		(stroke
			(width 0)
			(type default)
		)
	)
	(bus_entry
		(at 163.83 205.74)
		(size 2.54 -2.54)
		(stroke
			(width 0)
			(type default)
		)
	)
	(bus_entry
		(at 358.14 104.14)
		(size 2.54 2.54)
		(stroke
			(width 0)
			(type default)
		)
	)
	(bus_entry
		(at 163.83 196.85)
		(size 2.54 -2.54)
		(stroke
			(width 0)
			(type default)
		)
	)
	(bus_entry
		(at 163.83 190.5)
		(size 2.54 -2.54)
		(stroke
			(width 0)
			(type default)
		)
	)
	(bus_entry
		(at 163.83 180.34)
		(size 2.54 -2.54)
		(stroke
			(width 0)
			(type default)
		)
	)
	(bus_entry
		(at 163.83 144.78)
		(size 2.54 -2.54)
		(stroke
			(width 0)
			(type default)
		)
	)
	(bus_entry
		(at 163.83 172.72)
		(size 2.54 -2.54)
		(stroke
			(width 0)
			(type default)
		)
	)
	(bus
		(pts
			(xy 360.68 109.22) (xy 360.68 106.68)
		)
		(stroke
			(width 0)
			(type default)
		)
	)
	(wire
		(pts
			(xy 137.16 124.46) (xy 133.35 124.46)
		)
		(stroke
			(width 0)
			(type default)
		)
	)
	(wire
		(pts
			(xy 328.93 88.9) (xy 358.14 88.9)
		)
		(stroke
			(width 0)
			(type default)
		)
	)
	(wire
		(pts
			(xy 238.76 184.15) (xy 238.76 179.07)
		)
		(stroke
			(width 0)
			(type default)
		)
	)
	(wire
		(pts
			(xy 133.35 73.66) (xy 133.35 74.93)
		)
		(stroke
			(width 0)
			(type default)
		)
	)
	(wire
		(pts
			(xy 299.72 119.38) (xy 299.72 114.3)
		)
		(stroke
			(width 0)
			(type default)
		)
	)
	(wire
		(pts
			(xy 309.88 72.39) (xy 323.85 72.39)
		)
		(stroke
			(width 0)
			(type default)
		)
	)
	(wire
		(pts
			(xy 300.99 173.99) (xy 309.88 173.99)
		)
		(stroke
			(width 0)
			(type default)
		)
	)
	(wire
		(pts
			(xy 294.64 190.5) (xy 295.91 190.5)
		)
		(stroke
			(width 0)
			(type default)
		)
	)
	(wire
		(pts
			(xy 142.24 114.3) (xy 146.05 114.3)
		)
		(stroke
			(width 0)
			(type default)
		)
	)
	(bus
		(pts
			(xy 360.68 46.99) (xy 360.68 52.07)
		)
		(stroke
			(width 0)
			(type default)
		)
	)
	(wire
		(pts
			(xy 76.2 180.34) (xy 92.71 180.34)
		)
		(stroke
			(width 0)
			(type default)
		)
	)
	(wire
		(pts
			(xy 76.2 190.5) (xy 92.71 190.5)
		)
		(stroke
			(width 0)
			(type default)
		)
	)
	(wire
		(pts
			(xy 137.16 143.51) (xy 133.35 143.51)
		)
		(stroke
			(width 0)
			(type default)
		)
	)
	(wire
		(pts
			(xy 110.49 190.5) (xy 163.83 190.5)
		)
		(stroke
			(width 0)
			(type default)
		)
	)
	(wire
		(pts
			(xy 280.67 199.39) (xy 311.15 199.39)
		)
		(stroke
			(width 0)
			(type default)
		)
	)
	(bus
		(pts
			(xy 166.37 125.73) (xy 166.37 132.08)
		)
		(stroke
			(width 0)
			(type default)
		)
	)
	(wire
		(pts
			(xy 76.2 77.47) (xy 92.71 77.47)
		)
		(stroke
			(width 0)
			(type default)
		)
	)
	(wire
		(pts
			(xy 110.49 134.62) (xy 133.35 134.62)
		)
		(stroke
			(width 0)
			(type default)
		)
	)
	(wire
		(pts
			(xy 146.05 137.16) (xy 146.05 138.43)
		)
		(stroke
			(width 0)
			(type default)
		)
	)
	(wire
		(pts
			(xy 146.05 77.47) (xy 146.05 78.74)
		)
		(stroke
			(width 0)
			(type default)
		)
	)
	(wire
		(pts
			(xy 262.89 204.47) (xy 262.89 201.93)
		)
		(stroke
			(width 0)
			(type default)
		)
	)
	(wire
		(pts
			(xy 133.35 93.98) (xy 133.35 95.25)
		)
		(stroke
			(width 0)
			(type default)
		)
	)
	(wire
		(pts
			(xy 137.16 83.82) (xy 133.35 83.82)
		)
		(stroke
			(width 0)
			(type default)
		)
	)
	(wire
		(pts
			(xy 76.2 157.48) (xy 92.71 157.48)
		)
		(stroke
			(width 0)
			(type default)
		)
	)
	(wire
		(pts
			(xy 92.71 195.58) (xy 76.2 195.58)
		)
		(stroke
			(width 0)
			(type default)
		)
	)
	(wire
		(pts
			(xy 137.16 129.54) (xy 133.35 129.54)
		)
		(stroke
			(width 0)
			(type default)
		)
	)
	(wire
		(pts
			(xy 110.49 137.16) (xy 133.35 137.16)
		)
		(stroke
			(width 0)
			(type default)
		)
	)
	(wire
		(pts
			(xy 76.2 162.56) (xy 92.71 162.56)
		)
		(stroke
			(width 0)
			(type default)
		)
	)
	(wire
		(pts
			(xy 146.05 137.16) (xy 163.83 137.16)
		)
		(stroke
			(width 0)
			(type default)
		)
	)
	(wire
		(pts
			(xy 299.72 104.14) (xy 320.04 104.14)
		)
		(stroke
			(width 0)
			(type default)
		)
	)
	(bus
		(pts
			(xy 166.37 72.39) (xy 166.37 74.93)
		)
		(stroke
			(width 0)
			(type default)
		)
	)
	(wire
		(pts
			(xy 110.49 170.18) (xy 163.83 170.18)
		)
		(stroke
			(width 0)
			(type default)
		)
	)
	(bus
		(pts
			(xy 166.37 157.48) (xy 166.37 161.29)
		)
		(stroke
			(width 0)
			(type default)
		)
	)
	(wire
		(pts
			(xy 308.61 229.87) (xy 311.15 229.87)
		)
		(stroke
			(width 0)
			(type default)
		)
	)
	(wire
		(pts
			(xy 146.05 115.57) (xy 163.83 115.57)
		)
		(stroke
			(width 0)
			(type default)
		)
	)
	(wire
		(pts
			(xy 137.16 114.3) (xy 133.35 114.3)
		)
		(stroke
			(width 0)
			(type default)
		)
	)
	(bus
		(pts
			(xy 360.68 91.44) (xy 360.68 88.9)
		)
		(stroke
			(width 0)
			(type default)
		)
	)
	(wire
		(pts
			(xy 304.8 95.25) (xy 320.04 95.25)
		)
		(stroke
			(width 0)
			(type default)
		)
	)
	(wire
		(pts
			(xy 262.89 196.85) (xy 262.89 199.39)
		)
		(stroke
			(width 0)
			(type default)
		)
	)
	(wire
		(pts
			(xy 304.8 64.77) (xy 323.85 64.77)
		)
		(stroke
			(width 0)
			(type default)
		)
	)
	(wire
		(pts
			(xy 228.6 167.64) (xy 228.6 173.99)
		)
		(stroke
			(width 0)
			(type default)
		)
	)
	(wire
		(pts
			(xy 146.05 73.66) (xy 146.05 74.93)
		)
		(stroke
			(width 0)
			(type default)
		)
	)
	(wire
		(pts
			(xy 142.24 102.87) (xy 146.05 102.87)
		)
		(stroke
			(width 0)
			(type default)
		)
	)
	(bus
		(pts
			(xy 360.68 128.27) (xy 361.95 129.54)
		)
		(stroke
			(width 0)
			(type default)
		)
	)
	(bus
		(pts
			(xy 166.37 163.83) (xy 166.37 167.64)
		)
		(stroke
			(width 0)
			(type default)
		)
	)
	(wire
		(pts
			(xy 76.2 80.01) (xy 92.71 80.01)
		)
		(stroke
			(width 0)
			(type default)
		)
	)
	(bus
		(pts
			(xy 166.37 113.03) (xy 166.37 115.57)
		)
		(stroke
			(width 0)
			(type default)
		)
	)
	(wire
		(pts
			(xy 142.24 93.98) (xy 146.05 93.98)
		)
		(stroke
			(width 0)
			(type default)
		)
	)
	(wire
		(pts
			(xy 278.13 96.52) (xy 299.72 96.52)
		)
		(stroke
			(width 0)
			(type default)
		)
	)
	(wire
		(pts
			(xy 110.49 95.25) (xy 133.35 95.25)
		)
		(stroke
			(width 0)
			(type default)
		)
	)
	(wire
		(pts
			(xy 278.13 68.58) (xy 302.26 68.58)
		)
		(stroke
			(width 0)
			(type default)
		)
	)
	(wire
		(pts
			(xy 297.18 116.84) (xy 297.18 121.92)
		)
		(stroke
			(width 0)
			(type default)
		)
	)
	(wire
		(pts
			(xy 299.72 66.04) (xy 299.72 57.15)
		)
		(stroke
			(width 0)
			(type default)
		)
	)
	(wire
		(pts
			(xy 308.61 224.79) (xy 308.61 227.33)
		)
		(stroke
			(width 0)
			(type default)
		)
	)
	(wire
		(pts
			(xy 146.05 205.74) (xy 163.83 205.74)
		)
		(stroke
			(width 0)
			(type default)
		)
	)
	(wire
		(pts
			(xy 300.99 175.26) (xy 300.99 173.99)
		)
		(stroke
			(width 0)
			(type default)
		)
	)
	(wire
		(pts
			(xy 292.1 219.71) (xy 311.15 219.71)
		)
		(stroke
			(width 0)
			(type default)
		)
	)
	(bus
		(pts
			(xy 166.37 196.85) (xy 166.37 203.2)
		)
		(stroke
			(width 0)
			(type default)
		)
	)
	(wire
		(pts
			(xy 92.71 123.19) (xy 76.2 123.19)
		)
		(stroke
			(width 0)
			(type default)
		)
	)
	(wire
		(pts
			(xy 278.13 78.74) (xy 320.04 78.74)
		)
		(stroke
			(width 0)
			(type default)
		)
	)
	(wire
		(pts
			(xy 146.05 87.63) (xy 163.83 87.63)
		)
		(stroke
			(width 0)
			(type default)
		)
	)
	(wire
		(pts
			(xy 146.05 102.87) (xy 146.05 104.14)
		)
		(stroke
			(width 0)
			(type default)
		)
	)
	(wire
		(pts
			(xy 278.13 111.76) (xy 316.23 111.76)
		)
		(stroke
			(width 0)
			(type default)
		)
	)
	(wire
		(pts
			(xy 278.13 99.06) (xy 297.18 99.06)
		)
		(stroke
			(width 0)
			(type default)
		)
	)
	(wire
		(pts
			(xy 110.49 196.85) (xy 163.83 196.85)
		)
		(stroke
			(width 0)
			(type default)
		)
	)
	(bus
		(pts
			(xy 360.68 121.92) (xy 360.68 109.22)
		)
		(stroke
			(width 0)
			(type default)
		)
	)
	(wire
		(pts
			(xy 278.13 63.5) (xy 297.18 63.5)
		)
		(stroke
			(width 0)
			(type default)
		)
	)
	(wire
		(pts
			(xy 110.49 125.73) (xy 133.35 125.73)
		)
		(stroke
			(width 0)
			(type default)
		)
	)
	(wire
		(pts
			(xy 76.2 100.33) (xy 92.71 100.33)
		)
		(stroke
			(width 0)
			(type default)
		)
	)
	(wire
		(pts
			(xy 146.05 97.79) (xy 163.83 97.79)
		)
		(stroke
			(width 0)
			(type default)
		)
	)
	(wire
		(pts
			(xy 110.49 144.78) (xy 133.35 144.78)
		)
		(stroke
			(width 0)
			(type default)
		)
	)
	(wire
		(pts
			(xy 146.05 114.3) (xy 146.05 115.57)
		)
		(stroke
			(width 0)
			(type default)
		)
	)
	(wire
		(pts
			(xy 328.93 57.15) (xy 358.14 57.15)
		)
		(stroke
			(width 0)
			(type default)
		)
	)
	(wire
		(pts
			(xy 297.18 106.68) (xy 323.85 106.68)
		)
		(stroke
			(width 0)
			(type default)
		)
	)
	(wire
		(pts
			(xy 299.72 57.15) (xy 323.85 57.15)
		)
		(stroke
			(width 0)
			(type default)
		)
	)
	(wire
		(pts
			(xy 303.53 207.01) (xy 311.15 207.01)
		)
		(stroke
			(width 0)
			(type default)
		)
	)
	(wire
		(pts
			(xy 259.08 199.39) (xy 262.89 199.39)
		)
		(stroke
			(width 0)
			(type default)
		)
	)
	(wire
		(pts
			(xy 300.99 184.15) (xy 300.99 181.61)
		)
		(stroke
			(width 0)
			(type default)
		)
	)
	(wire
		(pts
			(xy 299.72 189.23) (xy 311.15 189.23)
		)
		(stroke
			(width 0)
			(type default)
		)
	)
	(wire
		(pts
			(xy 297.18 54.61) (xy 320.04 54.61)
		)
		(stroke
			(width 0)
			(type default)
		)
	)
	(wire
		(pts
			(xy 146.05 118.11) (xy 146.05 119.38)
		)
		(stroke
			(width 0)
			(type default)
		)
	)
	(bus
		(pts
			(xy 360.68 54.61) (xy 360.68 59.69)
		)
		(stroke
			(width 0)
			(type default)
		)
	)
	(wire
		(pts
			(xy 146.05 125.73) (xy 163.83 125.73)
		)
		(stroke
			(width 0)
			(type default)
		)
	)
	(wire
		(pts
			(xy 133.35 138.43) (xy 133.35 137.16)
		)
		(stroke
			(width 0)
			(type default)
		)
	)
	(bus
		(pts
			(xy 360.68 67.31) (xy 360.68 69.85)
		)
		(stroke
			(width 0)
			(type default)
		)
	)
	(wire
		(pts
			(xy 76.2 125.73) (xy 92.71 125.73)
		)
		(stroke
			(width 0)
			(type default)
		)
	)
	(bus
		(pts
			(xy 166.37 74.93) (xy 166.37 82.55)
		)
		(stroke
			(width 0)
			(type default)
		)
	)
	(wire
		(pts
			(xy 146.05 147.32) (xy 163.83 147.32)
		)
		(stroke
			(width 0)
			(type default)
		)
	)
	(wire
		(pts
			(xy 270.51 203.2) (xy 270.51 204.47)
		)
		(stroke
			(width 0)
			(type default)
		)
	)
	(wire
		(pts
			(xy 142.24 148.59) (xy 146.05 148.59)
		)
		(stroke
			(width 0)
			(type default)
		)
	)
	(bus
		(pts
			(xy 360.68 124.46) (xy 360.68 128.27)
		)
		(stroke
			(width 0)
			(type default)
		)
	)
	(wire
		(pts
			(xy 280.67 201.93) (xy 311.15 201.93)
		)
		(stroke
			(width 0)
			(type default)
		)
	)
	(wire
		(pts
			(xy 76.2 187.96) (xy 92.71 187.96)
		)
		(stroke
			(width 0)
			(type default)
		)
	)
	(wire
		(pts
			(xy 76.2 172.72) (xy 92.71 172.72)
		)
		(stroke
			(width 0)
			(type default)
		)
	)
	(wire
		(pts
			(xy 142.24 143.51) (xy 146.05 143.51)
		)
		(stroke
			(width 0)
			(type default)
		)
	)
	(wire
		(pts
			(xy 270.51 196.85) (xy 270.51 198.12)
		)
		(stroke
			(width 0)
			(type default)
		)
	)
	(wire
		(pts
			(xy 278.13 91.44) (xy 304.8 91.44)
		)
		(stroke
			(width 0)
			(type default)
		)
	)
	(bus
		(pts
			(xy 166.37 101.6) (xy 166.37 104.14)
		)
		(stroke
			(width 0)
			(type default)
		)
	)
	(wire
		(pts
			(xy 110.49 160.02) (xy 163.83 160.02)
		)
		(stroke
			(width 0)
			(type default)
		)
	)
	(wire
		(pts
			(xy 146.05 134.62) (xy 163.83 134.62)
		)
		(stroke
			(width 0)
			(type default)
		)
	)
	(wire
		(pts
			(xy 137.16 119.38) (xy 133.35 119.38)
		)
		(stroke
			(width 0)
			(type default)
		)
	)
	(bus
		(pts
			(xy 166.37 104.14) (xy 166.37 113.03)
		)
		(stroke
			(width 0)
			(type default)
		)
	)
	(bus
		(pts
			(xy 289.56 217.17) (xy 289.56 214.63)
		)
		(stroke
			(width 0)
			(type default)
		)
	)
	(bus
		(pts
			(xy 166.37 115.57) (xy 166.37 123.19)
		)
		(stroke
			(width 0)
			(type default)
		)
	)
	(wire
		(pts
			(xy 146.05 208.28) (xy 146.05 209.55)
		)
		(stroke
			(width 0)
			(type default)
		)
	)
	(wire
		(pts
			(xy 142.24 78.74) (xy 146.05 78.74)
		)
		(stroke
			(width 0)
			(type default)
		)
	)
	(wire
		(pts
			(xy 76.2 102.87) (xy 92.71 102.87)
		)
		(stroke
			(width 0)
			(type default)
		)
	)
	(wire
		(pts
			(xy 238.76 167.64) (xy 238.76 173.99)
		)
		(stroke
			(width 0)
			(type default)
		)
	)
	(wire
		(pts
			(xy 137.16 133.35) (xy 133.35 133.35)
		)
		(stroke
			(width 0)
			(type default)
		)
	)
	(wire
		(pts
			(xy 133.35 148.59) (xy 133.35 147.32)
		)
		(stroke
			(width 0)
			(type default)
		)
	)
	(wire
		(pts
			(xy 76.2 167.64) (xy 92.71 167.64)
		)
		(stroke
			(width 0)
			(type default)
		)
	)
	(wire
		(pts
			(xy 289.56 186.69) (xy 289.56 184.15)
		)
		(stroke
			(width 0)
			(type default)
		)
	)
	(wire
		(pts
			(xy 76.2 154.94) (xy 92.71 154.94)
		)
		(stroke
			(width 0)
			(type default)
		)
	)
	(bus
		(pts
			(xy 166.37 177.8) (xy 166.37 181.61)
		)
		(stroke
			(width 0)
			(type default)
		)
	)
	(wire
		(pts
			(xy 133.35 204.47) (xy 133.35 205.74)
		)
		(stroke
			(width 0)
			(type default)
		)
	)
	(wire
		(pts
			(xy 76.2 110.49) (xy 92.71 110.49)
		)
		(stroke
			(width 0)
			(type default)
		)
	)
	(wire
		(pts
			(xy 289.56 184.15) (xy 299.72 184.15)
		)
		(stroke
			(width 0)
			(type default)
		)
	)
	(wire
		(pts
			(xy 110.49 153.67) (xy 163.83 153.67)
		)
		(stroke
			(width 0)
			(type default)
		)
	)
	(bus
		(pts
			(xy 166.37 190.5) (xy 166.37 194.31)
		)
		(stroke
			(width 0)
			(type default)
		)
	)
	(wire
		(pts
			(xy 142.24 209.55) (xy 146.05 209.55)
		)
		(stroke
			(width 0)
			(type default)
		)
	)
	(wire
		(pts
			(xy 278.13 93.98) (xy 302.26 93.98)
		)
		(stroke
			(width 0)
			(type default)
		)
	)
	(wire
		(pts
			(xy 228.6 179.07) (xy 228.6 184.15)
		)
		(stroke
			(width 0)
			(type default)
		)
	)
	(wire
		(pts
			(xy 146.05 97.79) (xy 146.05 99.06)
		)
		(stroke
			(width 0)
			(type default)
		)
	)
	(wire
		(pts
			(xy 146.05 124.46) (xy 146.05 125.73)
		)
		(stroke
			(width 0)
			(type default)
		)
	)
	(bus
		(pts
			(xy 360.68 76.2) (xy 360.68 78.74)
		)
		(stroke
			(width 0)
			(type default)
		)
	)
	(wire
		(pts
			(xy 328.93 106.68) (xy 358.14 106.68)
		)
		(stroke
			(width 0)
			(type default)
		)
	)
	(wire
		(pts
			(xy 270.51 204.47) (xy 262.89 204.47)
		)
		(stroke
			(width 0)
			(type default)
		)
	)
	(wire
		(pts
			(xy 146.05 85.09) (xy 163.83 85.09)
		)
		(stroke
			(width 0)
			(type default)
		)
	)
	(wire
		(pts
			(xy 110.49 104.14) (xy 133.35 104.14)
		)
		(stroke
			(width 0)
			(type default)
		)
	)
	(wire
		(pts
			(xy 137.16 73.66) (xy 133.35 73.66)
		)
		(stroke
			(width 0)
			(type default)
		)
	)
	(wire
		(pts
			(xy 233.68 167.64) (xy 228.6 167.64)
		)
		(stroke
			(width 0)
			(type default)
		)
	)
	(wire
		(pts
			(xy 146.05 93.98) (xy 146.05 95.25)
		)
		(stroke
			(width 0)
			(type default)
		)
	)
	(wire
		(pts
			(xy 325.12 86.36) (xy 358.14 86.36)
		)
		(stroke
			(width 0)
			(type default)
		)
	)
	(wire
		(pts
			(xy 299.72 114.3) (xy 278.13 114.3)
		)
		(stroke
			(width 0)
			(type default)
		)
	)
	(bus
		(pts
			(xy 166.37 82.55) (xy 166.37 85.09)
		)
		(stroke
			(width 0)
			(type default)
		)
	)
	(wire
		(pts
			(xy 142.24 124.46) (xy 146.05 124.46)
		)
		(stroke
			(width 0)
			(type default)
		)
	)
	(wire
		(pts
			(xy 76.2 185.42) (xy 92.71 185.42)
		)
		(stroke
			(width 0)
			(type default)
		)
	)
	(wire
		(pts
			(xy 299.72 184.15) (xy 299.72 189.23)
		)
		(stroke
			(width 0)
			(type default)
		)
	)
	(wire
		(pts
			(xy 110.49 115.57) (xy 133.35 115.57)
		)
		(stroke
			(width 0)
			(type default)
		)
	)
	(wire
		(pts
			(xy 76.2 105.41) (xy 92.71 105.41)
		)
		(stroke
			(width 0)
			(type default)
		)
	)
	(wire
		(pts
			(xy 133.35 107.95) (xy 137.16 107.95)
		)
		(stroke
			(width 0)
			(type default)
		)
	)
	(wire
		(pts
			(xy 133.35 99.06) (xy 133.35 97.79)
		)
		(stroke
			(width 0)
			(type default)
		)
	)
	(wire
		(pts
			(xy 76.2 115.57) (xy 92.71 115.57)
		)
		(stroke
			(width 0)
			(type default)
		)
	)
	(bus
		(pts
			(xy 166.37 203.2) (xy 166.37 205.74)
		)
		(stroke
			(width 0)
			(type default)
		)
	)
	(bus
		(pts
			(xy 285.75 210.82) (xy 288.29 210.82)
		)
		(stroke
			(width 0)
			(type default)
		)
	)
	(wire
		(pts
			(xy 325.12 104.14) (xy 358.14 104.14)
		)
		(stroke
			(width 0)
			(type default)
		)
	)
	(wire
		(pts
			(xy 278.13 76.2) (xy 309.88 76.2)
		)
		(stroke
			(width 0)
			(type default)
		)
	)
	(wire
		(pts
			(xy 76.2 170.18) (xy 92.71 170.18)
		)
		(stroke
			(width 0)
			(type default)
		)
	)
	(wire
		(pts
			(xy 137.16 88.9) (xy 133.35 88.9)
		)
		(stroke
			(width 0)
			(type default)
		)
	)
	(wire
		(pts
			(xy 110.49 186.69) (xy 163.83 186.69)
		)
		(stroke
			(width 0)
			(type default)
		)
	)
	(wire
		(pts
			(xy 328.93 81.28) (xy 358.14 81.28)
		)
		(stroke
			(width 0)
			(type default)
		)
	)
	(wire
		(pts
			(xy 110.49 163.83) (xy 163.83 163.83)
		)
		(stroke
			(width 0)
			(type default)
		)
	)
	(wire
		(pts
			(xy 137.16 209.55) (xy 133.35 209.55)
		)
		(stroke
			(width 0)
			(type default)
		)
	)
	(wire
		(pts
			(xy 110.49 166.37) (xy 163.83 166.37)
		)
		(stroke
			(width 0)
			(type default)
		)
	)
	(wire
		(pts
			(xy 133.35 88.9) (xy 133.35 87.63)
		)
		(stroke
			(width 0)
			(type default)
		)
	)
	(bus
		(pts
			(xy 166.37 95.25) (xy 166.37 101.6)
		)
		(stroke
			(width 0)
			(type default)
		)
	)
	(bus
		(pts
			(xy 166.37 85.09) (xy 166.37 92.71)
		)
		(stroke
			(width 0)
			(type default)
		)
	)
	(wire
		(pts
			(xy 110.49 172.72) (xy 163.83 172.72)
		)
		(stroke
			(width 0)
			(type default)
		)
	)
	(wire
		(pts
			(xy 278.13 88.9) (xy 323.85 88.9)
		)
		(stroke
			(width 0)
			(type default)
		)
	)
	(bus
		(pts
			(xy 360.68 69.85) (xy 360.68 76.2)
		)
		(stroke
			(width 0)
			(type default)
		)
	)
	(wire
		(pts
			(xy 133.35 209.55) (xy 133.35 208.28)
		)
		(stroke
			(width 0)
			(type default)
		)
	)
	(wire
		(pts
			(xy 146.05 95.25) (xy 163.83 95.25)
		)
		(stroke
			(width 0)
			(type default)
		)
	)
	(wire
		(pts
			(xy 328.93 97.79) (xy 358.14 97.79)
		)
		(stroke
			(width 0)
			(type default)
		)
	)
	(wire
		(pts
			(xy 278.13 73.66) (xy 307.34 73.66)
		)
		(stroke
			(width 0)
			(type default)
		)
	)
	(wire
		(pts
			(xy 133.35 143.51) (xy 133.35 144.78)
		)
		(stroke
			(width 0)
			(type default)
		)
	)
	(wire
		(pts
			(xy 110.49 85.09) (xy 133.35 85.09)
		)
		(stroke
			(width 0)
			(type default)
		)
	)
	(wire
		(pts
			(xy 133.35 107.95) (xy 133.35 106.68)
		)
		(stroke
			(width 0)
			(type default)
		)
	)
	(wire
		(pts
			(xy 233.68 167.64) (xy 233.68 173.99)
		)
		(stroke
			(width 0)
			(type default)
		)
	)
	(wire
		(pts
			(xy 146.05 144.78) (xy 163.83 144.78)
		)
		(stroke
			(width 0)
			(type default)
		)
	)
	(wire
		(pts
			(xy 278.13 109.22) (xy 316.23 109.22)
		)
		(stroke
			(width 0)
			(type default)
		)
	)
	(bus
		(pts
			(xy 166.37 66.04) (xy 167.64 64.77)
		)
		(stroke
			(width 0)
			(type default)
		)
	)
	(wire
		(pts
			(xy 370.84 201.93) (xy 394.97 201.93)
		)
		(stroke
			(width 0)
			(type default)
		)
	)
	(bus
		(pts
			(xy 166.37 142.24) (xy 166.37 144.78)
		)
		(stroke
			(width 0)
			(type default)
		)
	)
	(wire
		(pts
			(xy 76.2 107.95) (xy 92.71 107.95)
		)
		(stroke
			(width 0)
			(type default)
		)
	)
	(wire
		(pts
			(xy 308.61 234.95) (xy 308.61 241.3)
		)
		(stroke
			(width 0)
			(type default)
		)
	)
	(wire
		(pts
			(xy 308.61 234.95) (xy 308.61 229.87)
		)
		(stroke
			(width 0)
			(type default)
		)
	)
	(wire
		(pts
			(xy 110.49 151.13) (xy 163.83 151.13)
		)
		(stroke
			(width 0)
			(type default)
		)
	)
	(wire
		(pts
			(xy 302.26 93.98) (xy 302.26 97.79)
		)
		(stroke
			(width 0)
			(type default)
		)
	)
	(wire
		(pts
			(xy 146.05 104.14) (xy 163.83 104.14)
		)
		(stroke
			(width 0)
			(type default)
		)
	)
	(bus
		(pts
			(xy 166.37 134.62) (xy 166.37 142.24)
		)
		(stroke
			(width 0)
			(type default)
		)
	)
	(bus
		(pts
			(xy 360.68 59.69) (xy 360.68 62.23)
		)
		(stroke
			(width 0)
			(type default)
		)
	)
	(wire
		(pts
			(xy 146.05 106.68) (xy 163.83 106.68)
		)
		(stroke
			(width 0)
			(type default)
		)
	)
	(bus
		(pts
			(xy 166.37 181.61) (xy 166.37 184.15)
		)
		(stroke
			(width 0)
			(type default)
		)
	)
	(wire
		(pts
			(xy 278.13 116.84) (xy 297.18 116.84)
		)
		(stroke
			(width 0)
			(type default)
		)
	)
	(wire
		(pts
			(xy 223.52 167.64) (xy 223.52 173.99)
		)
		(stroke
			(width 0)
			(type default)
		)
	)
	(wire
		(pts
			(xy 142.24 204.47) (xy 146.05 204.47)
		)
		(stroke
			(width 0)
			(type default)
		)
	)
	(wire
		(pts
			(xy 146.05 128.27) (xy 146.05 129.54)
		)
		(stroke
			(width 0)
			(type default)
		)
	)
	(wire
		(pts
			(xy 76.2 113.03) (xy 92.71 113.03)
		)
		(stroke
			(width 0)
			(type default)
		)
	)
	(wire
		(pts
			(xy 325.12 78.74) (xy 358.14 78.74)
		)
		(stroke
			(width 0)
			(type default)
		)
	)
	(wire
		(pts
			(xy 110.49 205.74) (xy 133.35 205.74)
		)
		(stroke
			(width 0)
			(type default)
		)
	)
	(wire
		(pts
			(xy 76.2 95.25) (xy 92.71 95.25)
		)
		(stroke
			(width 0)
			(type default)
		)
	)
	(bus
		(pts
			(xy 166.37 175.26) (xy 166.37 177.8)
		)
		(stroke
			(width 0)
			(type default)
		)
	)
	(wire
		(pts
			(xy 325.12 62.23) (xy 358.14 62.23)
		)
		(stroke
			(width 0)
			(type default)
		)
	)
	(wire
		(pts
			(xy 137.16 102.87) (xy 133.35 102.87)
		)
		(stroke
			(width 0)
			(type default)
		)
	)
	(bus
		(pts
			(xy 166.37 151.13) (xy 166.37 154.94)
		)
		(stroke
			(width 0)
			(type default)
		)
	)
	(wire
		(pts
			(xy 302.26 68.58) (xy 302.26 62.23)
		)
		(stroke
			(width 0)
			(type default)
		)
	)
	(wire
		(pts
			(xy 76.2 92.71) (xy 92.71 92.71)
		)
		(stroke
			(width 0)
			(type default)
		)
	)
	(wire
		(pts
			(xy 308.61 227.33) (xy 311.15 227.33)
		)
		(stroke
			(width 0)
			(type default)
		)
	)
	(wire
		(pts
			(xy 270.51 196.85) (xy 274.32 196.85)
		)
		(stroke
			(width 0)
			(type default)
		)
	)
	(bus
		(pts
			(xy 166.37 187.96) (xy 166.37 190.5)
		)
		(stroke
			(width 0)
			(type default)
		)
	)
	(wire
		(pts
			(xy 223.52 167.64) (xy 228.6 167.64)
		)
		(stroke
			(width 0)
			(type default)
		)
	)
	(wire
		(pts
			(xy 223.52 179.07) (xy 223.52 184.15)
		)
		(stroke
			(width 0)
			(type default)
		)
	)
	(bus
		(pts
			(xy 360.68 124.46) (xy 360.68 121.92)
		)
		(stroke
			(width 0)
			(type default)
		)
	)
	(wire
		(pts
			(xy 76.2 182.88) (xy 92.71 182.88)
		)
		(stroke
			(width 0)
			(type default)
		)
	)
	(bus
		(pts
			(xy 360.68 52.07) (xy 360.68 54.61)
		)
		(stroke
			(width 0)
			(type default)
		)
	)
	(bus
		(pts
			(xy 289.56 212.09) (xy 288.29 210.82)
		)
		(stroke
			(width 0)
			(type default)
		)
	)
	(wire
		(pts
			(xy 289.56 194.31) (xy 289.56 196.85)
		)
		(stroke
			(width 0)
			(type default)
		)
	)
	(wire
		(pts
			(xy 223.52 162.56) (xy 223.52 167.64)
		)
		(stroke
			(width 0)
			(type default)
		)
	)
	(wire
		(pts
			(xy 278.13 71.12) (xy 304.8 71.12)
		)
		(stroke
			(width 0)
			(type default)
		)
	)
	(wire
		(pts
			(xy 110.49 193.04) (xy 163.83 193.04)
		)
		(stroke
			(width 0)
			(type default)
		)
	)
	(wire
		(pts
			(xy 110.49 87.63) (xy 133.35 87.63)
		)
		(stroke
			(width 0)
			(type default)
		)
	)
	(wire
		(pts
			(xy 238.76 167.64) (xy 233.68 167.64)
		)
		(stroke
			(width 0)
			(type default)
		)
	)
	(wire
		(pts
			(xy 146.05 118.11) (xy 163.83 118.11)
		)
		(stroke
			(width 0)
			(type default)
		)
	)
	(wire
		(pts
			(xy 110.49 147.32) (xy 133.35 147.32)
		)
		(stroke
			(width 0)
			(type default)
		)
	)
	(bus
		(pts
			(xy 166.37 161.29) (xy 166.37 163.83)
		)
		(stroke
			(width 0)
			(type default)
		)
	)
	(wire
		(pts
			(xy 133.35 129.54) (xy 133.35 128.27)
		)
		(stroke
			(width 0)
			(type default)
		)
	)
	(wire
		(pts
			(xy 137.16 204.47) (xy 133.35 204.47)
		)
		(stroke
			(width 0)
			(type default)
		)
	)
	(wire
		(pts
			(xy 142.24 73.66) (xy 146.05 73.66)
		)
		(stroke
			(width 0)
			(type default)
		)
	)
	(wire
		(pts
			(xy 304.8 91.44) (xy 304.8 95.25)
		)
		(stroke
			(width 0)
			(type default)
		)
	)
	(wire
		(pts
			(xy 110.49 208.28) (xy 133.35 208.28)
		)
		(stroke
			(width 0)
			(type default)
		)
	)
	(wire
		(pts
			(xy 325.12 95.25) (xy 358.14 95.25)
		)
		(stroke
			(width 0)
			(type default)
		)
	)
	(wire
		(pts
			(xy 146.05 106.68) (xy 146.05 107.95)
		)
		(stroke
			(width 0)
			(type default)
		)
	)
	(wire
		(pts
			(xy 76.2 82.55) (xy 92.71 82.55)
		)
		(stroke
			(width 0)
			(type default)
		)
	)
	(wire
		(pts
			(xy 146.05 147.32) (xy 146.05 148.59)
		)
		(stroke
			(width 0)
			(type default)
		)
	)
	(wire
		(pts
			(xy 146.05 133.35) (xy 146.05 134.62)
		)
		(stroke
			(width 0)
			(type default)
		)
	)
	(wire
		(pts
			(xy 299.72 119.38) (xy 321.31 119.38)
		)
		(stroke
			(width 0)
			(type default)
		)
	)
	(wire
		(pts
			(xy 307.34 69.85) (xy 320.04 69.85)
		)
		(stroke
			(width 0)
			(type default)
		)
	)
	(wire
		(pts
			(xy 278.13 66.04) (xy 299.72 66.04)
		)
		(stroke
			(width 0)
			(type default)
		)
	)
	(wire
		(pts
			(xy 302.26 62.23) (xy 320.04 62.23)
		)
		(stroke
			(width 0)
			(type default)
		)
	)
	(wire
		(pts
			(xy 133.35 133.35) (xy 133.35 134.62)
		)
		(stroke
			(width 0)
			(type default)
		)
	)
	(wire
		(pts
			(xy 110.49 97.79) (xy 133.35 97.79)
		)
		(stroke
			(width 0)
			(type default)
		)
	)
	(wire
		(pts
			(xy 233.68 184.15) (xy 233.68 179.07)
		)
		(stroke
			(width 0)
			(type default)
		)
	)
	(bus
		(pts
			(xy 166.37 184.15) (xy 166.37 187.96)
		)
		(stroke
			(width 0)
			(type default)
		)
	)
	(wire
		(pts
			(xy 334.01 199.39) (xy 363.22 199.39)
		)
		(stroke
			(width 0)
			(type default)
		)
	)
	(wire
		(pts
			(xy 311.15 184.15) (xy 300.99 184.15)
		)
		(stroke
			(width 0)
			(type default)
		)
	)
	(wire
		(pts
			(xy 110.49 128.27) (xy 133.35 128.27)
		)
		(stroke
			(width 0)
			(type default)
		)
	)
	(wire
		(pts
			(xy 297.18 54.61) (xy 297.18 63.5)
		)
		(stroke
			(width 0)
			(type default)
		)
	)
	(bus
		(pts
			(xy 360.68 97.79) (xy 360.68 91.44)
		)
		(stroke
			(width 0)
			(type default)
		)
	)
	(wire
		(pts
			(xy 334.01 234.95) (xy 339.09 234.95)
		)
		(stroke
			(width 0)
			(type default)
		)
	)
	(wire
		(pts
			(xy 368.3 199.39) (xy 394.97 199.39)
		)
		(stroke
			(width 0)
			(type default)
		)
	)
	(wire
		(pts
			(xy 295.91 190.5) (xy 295.91 191.77)
		)
		(stroke
			(width 0)
			(type default)
		)
	)
	(bus
		(pts
			(xy 360.68 106.68) (xy 360.68 100.33)
		)
		(stroke
			(width 0)
			(type default)
		)
	)
	(bus
		(pts
			(xy 166.37 92.71) (xy 166.37 95.25)
		)
		(stroke
			(width 0)
			(type default)
		)
	)
	(wire
		(pts
			(xy 110.49 118.11) (xy 133.35 118.11)
		)
		(stroke
			(width 0)
			(type default)
		)
	)
	(wire
		(pts
			(xy 76.2 85.09) (xy 92.71 85.09)
		)
		(stroke
			(width 0)
			(type default)
		)
	)
	(bus
		(pts
			(xy 166.37 148.59) (xy 166.37 151.13)
		)
		(stroke
			(width 0)
			(type default)
		)
	)
	(wire
		(pts
			(xy 110.49 199.39) (xy 163.83 199.39)
		)
		(stroke
			(width 0)
			(type default)
		)
	)
	(bus
		(pts
			(xy 167.64 64.77) (xy 170.18 64.77)
		)
		(stroke
			(width 0)
			(type default)
		)
	)
	(wire
		(pts
			(xy 309.88 163.83) (xy 309.88 173.99)
		)
		(stroke
			(width 0)
			(type default)
		)
	)
	(wire
		(pts
			(xy 289.56 196.85) (xy 299.72 196.85)
		)
		(stroke
			(width 0)
			(type default)
		)
	)
	(bus
		(pts
			(xy 166.37 170.18) (xy 166.37 175.26)
		)
		(stroke
			(width 0)
			(type default)
		)
	)
	(wire
		(pts
			(xy 142.24 83.82) (xy 146.05 83.82)
		)
		(stroke
			(width 0)
			(type default)
		)
	)
	(wire
		(pts
			(xy 259.08 201.93) (xy 262.89 201.93)
		)
		(stroke
			(width 0)
			(type default)
		)
	)
	(wire
		(pts
			(xy 308.61 196.85) (xy 308.61 224.79)
		)
		(stroke
			(width 0)
			(type default)
		)
	)
	(wire
		(pts
			(xy 328.93 72.39) (xy 358.14 72.39)
		)
		(stroke
			(width 0)
			(type default)
		)
	)
	(wire
		(pts
			(xy 133.35 119.38) (xy 133.35 118.11)
		)
		(stroke
			(width 0)
			(type default)
		)
	)
	(wire
		(pts
			(xy 133.35 114.3) (xy 133.35 115.57)
		)
		(stroke
			(width 0)
			(type default)
		)
	)
	(polyline
		(pts
			(xy 209.55 140.97) (xy 407.67 140.97)
		)
		(stroke
			(width 0)
			(type default)
		)
	)
	(wire
		(pts
			(xy 142.24 138.43) (xy 146.05 138.43)
		)
		(stroke
			(width 0)
			(type default)
		)
	)
	(wire
		(pts
			(xy 325.12 69.85) (xy 358.14 69.85)
		)
		(stroke
			(width 0)
			(type default)
		)
	)
	(bus
		(pts
			(xy 166.37 167.64) (xy 166.37 170.18)
		)
		(stroke
			(width 0)
			(type default)
		)
	)
	(wire
		(pts
			(xy 146.05 128.27) (xy 163.83 128.27)
		)
		(stroke
			(width 0)
			(type default)
		)
	)
	(bus
		(pts
			(xy 360.68 100.33) (xy 360.68 97.79)
		)
		(stroke
			(width 0)
			(type default)
		)
	)
	(wire
		(pts
			(xy 279.4 181.61) (xy 300.99 181.61)
		)
		(stroke
			(width 0)
			(type default)
		)
	)
	(wire
		(pts
			(xy 300.99 232.41) (xy 300.99 233.68)
		)
		(stroke
			(width 0)
			(type default)
		)
	)
	(wire
		(pts
			(xy 146.05 87.63) (xy 146.05 88.9)
		)
		(stroke
			(width 0)
			(type default)
		)
	)
	(bus
		(pts
			(xy 289.56 212.09) (xy 289.56 214.63)
		)
		(stroke
			(width 0)
			(type default)
		)
	)
	(wire
		(pts
			(xy 309.88 181.61) (xy 311.15 181.61)
		)
		(stroke
			(width 0)
			(type default)
		)
	)
	(wire
		(pts
			(xy 146.05 83.82) (xy 146.05 85.09)
		)
		(stroke
			(width 0)
			(type default)
		)
	)
	(wire
		(pts
			(xy 311.15 196.85) (xy 308.61 196.85)
		)
		(stroke
			(width 0)
			(type default)
		)
	)
	(wire
		(pts
			(xy 137.16 99.06) (xy 133.35 99.06)
		)
		(stroke
			(width 0)
			(type default)
		)
	)
	(wire
		(pts
			(xy 142.24 99.06) (xy 146.05 99.06)
		)
		(stroke
			(width 0)
			(type default)
		)
	)
	(wire
		(pts
			(xy 299.72 96.52) (xy 299.72 104.14)
		)
		(stroke
			(width 0)
			(type default)
		)
	)
	(bus
		(pts
			(xy 360.68 62.23) (xy 360.68 67.31)
		)
		(stroke
			(width 0)
			(type default)
		)
	)
	(wire
		(pts
			(xy 137.16 138.43) (xy 133.35 138.43)
		)
		(stroke
			(width 0)
			(type default)
		)
	)
	(wire
		(pts
			(xy 133.35 102.87) (xy 133.35 104.14)
		)
		(stroke
			(width 0)
			(type default)
		)
	)
	(wire
		(pts
			(xy 278.13 81.28) (xy 323.85 81.28)
		)
		(stroke
			(width 0)
			(type default)
		)
	)
	(wire
		(pts
			(xy 308.61 227.33) (xy 308.61 229.87)
		)
		(stroke
			(width 0)
			(type default)
		)
	)
	(bus
		(pts
			(xy 166.37 144.78) (xy 166.37 148.59)
		)
		(stroke
			(width 0)
			(type default)
		)
	)
	(bus
		(pts
			(xy 166.37 194.31) (xy 166.37 196.85)
		)
		(stroke
			(width 0)
			(type default)
		)
	)
	(wire
		(pts
			(xy 326.39 119.38) (xy 358.14 119.38)
		)
		(stroke
			(width 0)
			(type default)
		)
	)
	(wire
		(pts
			(xy 307.34 73.66) (xy 307.34 69.85)
		)
		(stroke
			(width 0)
			(type default)
		)
	)
	(wire
		(pts
			(xy 110.49 74.93) (xy 133.35 74.93)
		)
		(stroke
			(width 0)
			(type default)
		)
	)
	(wire
		(pts
			(xy 280.67 201.93) (xy 280.67 204.47)
		)
		(stroke
			(width 0)
			(type default)
		)
	)
	(wire
		(pts
			(xy 142.24 129.54) (xy 146.05 129.54)
		)
		(stroke
			(width 0)
			(type default)
		)
	)
	(wire
		(pts
			(xy 133.35 83.82) (xy 133.35 85.09)
		)
		(stroke
			(width 0)
			(type default)
		)
	)
	(wire
		(pts
			(xy 146.05 77.47) (xy 163.83 77.47)
		)
		(stroke
			(width 0)
			(type default)
		)
	)
	(wire
		(pts
			(xy 280.67 204.47) (xy 279.4 204.47)
		)
		(stroke
			(width 0)
			(type default)
		)
	)
	(wire
		(pts
			(xy 142.24 119.38) (xy 146.05 119.38)
		)
		(stroke
			(width 0)
			(type default)
		)
	)
	(wire
		(pts
			(xy 309.88 173.99) (xy 309.88 181.61)
		)
		(stroke
			(width 0)
			(type default)
		)
	)
	(polyline
		(pts
			(xy 209.55 284.48) (xy 209.55 12.7)
		)
		(stroke
			(width 0)
			(type default)
		)
	)
	(wire
		(pts
			(xy 300.99 232.41) (xy 311.15 232.41)
		)
		(stroke
			(width 0)
			(type default)
		)
	)
	(wire
		(pts
			(xy 308.61 224.79) (xy 311.15 224.79)
		)
		(stroke
			(width 0)
			(type default)
		)
	)
	(wire
		(pts
			(xy 110.49 184.15) (xy 163.83 184.15)
		)
		(stroke
			(width 0)
			(type default)
		)
	)
	(wire
		(pts
			(xy 142.24 107.95) (xy 146.05 107.95)
		)
		(stroke
			(width 0)
			(type default)
		)
	)
	(wire
		(pts
			(xy 110.49 77.47) (xy 133.35 77.47)
		)
		(stroke
			(width 0)
			(type default)
		)
	)
	(wire
		(pts
			(xy 133.35 78.74) (xy 133.35 77.47)
		)
		(stroke
			(width 0)
			(type default)
		)
	)
	(wire
		(pts
			(xy 297.18 121.92) (xy 325.12 121.92)
		)
		(stroke
			(width 0)
			(type default)
		)
	)
	(wire
		(pts
			(xy 146.05 143.51) (xy 146.05 144.78)
		)
		(stroke
			(width 0)
			(type default)
		)
	)
	(wire
		(pts
			(xy 297.18 106.68) (xy 297.18 99.06)
		)
		(stroke
			(width 0)
			(type default)
		)
	)
	(wire
		(pts
			(xy 76.2 87.63) (xy 92.71 87.63)
		)
		(stroke
			(width 0)
			(type default)
		)
	)
	(wire
		(pts
			(xy 334.01 232.41) (xy 339.09 232.41)
		)
		(stroke
			(width 0)
			(type default)
		)
	)
	(wire
		(pts
			(xy 299.72 191.77) (xy 311.15 191.77)
		)
		(stroke
			(width 0)
			(type default)
		)
	)
	(wire
		(pts
			(xy 76.2 165.1) (xy 92.71 165.1)
		)
		(stroke
			(width 0)
			(type default)
		)
	)
	(wire
		(pts
			(xy 110.49 180.34) (xy 163.83 180.34)
		)
		(stroke
			(width 0)
			(type default)
		)
	)
	(wire
		(pts
			(xy 137.16 78.74) (xy 133.35 78.74)
		)
		(stroke
			(width 0)
			(type default)
		)
	)
	(wire
		(pts
			(xy 110.49 106.68) (xy 133.35 106.68)
		)
		(stroke
			(width 0)
			(type default)
		)
	)
	(wire
		(pts
			(xy 76.2 177.8) (xy 92.71 177.8)
		)
		(stroke
			(width 0)
			(type default)
		)
	)
	(wire
		(pts
			(xy 76.2 90.17) (xy 92.71 90.17)
		)
		(stroke
			(width 0)
			(type default)
		)
	)
	(bus
		(pts
			(xy 166.37 154.94) (xy 166.37 157.48)
		)
		(stroke
			(width 0)
			(type default)
		)
	)
	(wire
		(pts
			(xy 302.26 97.79) (xy 323.85 97.79)
		)
		(stroke
			(width 0)
			(type default)
		)
	)
	(wire
		(pts
			(xy 270.51 204.47) (xy 274.32 204.47)
		)
		(stroke
			(width 0)
			(type default)
		)
	)
	(wire
		(pts
			(xy 133.35 124.46) (xy 133.35 125.73)
		)
		(stroke
			(width 0)
			(type default)
		)
	)
	(wire
		(pts
			(xy 304.8 71.12) (xy 304.8 64.77)
		)
		(stroke
			(width 0)
			(type default)
		)
	)
	(wire
		(pts
			(xy 137.16 93.98) (xy 133.35 93.98)
		)
		(stroke
			(width 0)
			(type default)
		)
	)
	(bus
		(pts
			(xy 361.95 45.72) (xy 365.76 45.72)
		)
		(stroke
			(width 0)
			(type default)
		)
	)
	(wire
		(pts
			(xy 280.67 196.85) (xy 280.67 199.39)
		)
		(stroke
			(width 0)
			(type default)
		)
	)
	(wire
		(pts
			(xy 280.67 196.85) (xy 279.4 196.85)
		)
		(stroke
			(width 0)
			(type default)
		)
	)
	(wire
		(pts
			(xy 309.88 72.39) (xy 309.88 76.2)
		)
		(stroke
			(width 0)
			(type default)
		)
	)
	(bus
		(pts
			(xy 166.37 123.19) (xy 166.37 125.73)
		)
		(stroke
			(width 0)
			(type default)
		)
	)
	(wire
		(pts
			(xy 328.93 64.77) (xy 358.14 64.77)
		)
		(stroke
			(width 0)
			(type default)
		)
	)
	(bus
		(pts
			(xy 166.37 66.04) (xy 166.37 72.39)
		)
		(stroke
			(width 0)
			(type default)
		)
	)
	(wire
		(pts
			(xy 110.49 177.8) (xy 163.83 177.8)
		)
		(stroke
			(width 0)
			(type default)
		)
	)
	(wire
		(pts
			(xy 334.01 201.93) (xy 365.76 201.93)
		)
		(stroke
			(width 0)
			(type default)
		)
	)
	(wire
		(pts
			(xy 311.15 234.95) (xy 308.61 234.95)
		)
		(stroke
			(width 0)
			(type default)
		)
	)
	(wire
		(pts
			(xy 299.72 196.85) (xy 299.72 191.77)
		)
		(stroke
			(width 0)
			(type default)
		)
	)
	(wire
		(pts
			(xy 303.53 209.55) (xy 311.15 209.55)
		)
		(stroke
			(width 0)
			(type default)
		)
	)
	(wire
		(pts
			(xy 325.12 54.61) (xy 358.14 54.61)
		)
		(stroke
			(width 0)
			(type default)
		)
	)
	(wire
		(pts
			(xy 110.49 157.48) (xy 163.83 157.48)
		)
		(stroke
			(width 0)
			(type default)
		)
	)
	(wire
		(pts
			(xy 146.05 208.28) (xy 163.83 208.28)
		)
		(stroke
			(width 0)
			(type default)
		)
	)
	(wire
		(pts
			(xy 137.16 148.59) (xy 133.35 148.59)
		)
		(stroke
			(width 0)
			(type default)
		)
	)
	(wire
		(pts
			(xy 142.24 88.9) (xy 146.05 88.9)
		)
		(stroke
			(width 0)
			(type default)
		)
	)
	(wire
		(pts
			(xy 278.13 86.36) (xy 320.04 86.36)
		)
		(stroke
			(width 0)
			(type default)
		)
	)
	(wire
		(pts
			(xy 92.71 118.11) (xy 76.2 118.11)
		)
		(stroke
			(width 0)
			(type default)
		)
	)
	(wire
		(pts
			(xy 142.24 133.35) (xy 146.05 133.35)
		)
		(stroke
			(width 0)
			(type default)
		)
	)
	(wire
		(pts
			(xy 292.1 217.17) (xy 311.15 217.17)
		)
		(stroke
			(width 0)
			(type default)
		)
	)
	(bus
		(pts
			(xy 166.37 132.08) (xy 166.37 134.62)
		)
		(stroke
			(width 0)
			(type default)
		)
	)
	(wire
		(pts
			(xy 146.05 74.93) (xy 163.83 74.93)
		)
		(stroke
			(width 0)
			(type default)
		)
	)
	(wire
		(pts
			(xy 300.99 241.3) (xy 300.99 238.76)
		)
		(stroke
			(width 0)
			(type default)
		)
	)
	(bus
		(pts
			(xy 360.68 46.99) (xy 361.95 45.72)
		)
		(stroke
			(width 0)
			(type default)
		)
	)
	(wire
		(pts
			(xy 146.05 204.47) (xy 146.05 205.74)
		)
		(stroke
			(width 0)
			(type default)
		)
	)
	(wire
		(pts
			(xy 330.2 121.92) (xy 358.14 121.92)
		)
		(stroke
			(width 0)
			(type default)
		)
	)
	(wire
		(pts
			(xy 76.2 193.04) (xy 92.71 193.04)
		)
		(stroke
			(width 0)
			(type default)
		)
	)
	(wire
		(pts
			(xy 300.99 181.61) (xy 300.99 180.34)
		)
		(stroke
			(width 0)
			(type default)
		)
	)
	(bus
		(pts
			(xy 365.76 129.54) (xy 361.95 129.54)
		)
		(stroke
			(width 0)
			(type default)
		)
	)
	(wire
		(pts
			(xy 270.51 196.85) (xy 262.89 196.85)
		)
		(stroke
			(width 0)
			(type default)
		)
	)
	(wire
		(pts
			(xy 76.2 160.02) (xy 92.71 160.02)
		)
		(stroke
			(width 0)
			(type default)
		)
	)
	(label "GTY_225_TX2_P"
		(at 92.71 165.1 180)
		(effects
			(font
				(size 1.27 1.27)
			)
			(justify right bottom)
		)
	)
	(label "GTY_225_RX2_P"
		(at 110.49 190.5 0)
		(effects
			(font
				(size 1.27 1.27)
			)
			(justify left bottom)
		)
	)
	(label "GTY_225_RX1_N"
		(at 110.49 186.69 0)
		(effects
			(font
				(size 1.27 1.27)
			)
			(justify left bottom)
		)
	)
	(label "PCIE.TXD5_N"
		(at 163.83 97.79 180)
		(effects
			(font
				(size 1.27 1.27)
			)
			(justify right bottom)
		)
	)
	(label "PCIE.TXD2_N"
		(at 163.83 128.27 180)
		(effects
			(font
				(size 1.27 1.27)
			)
			(justify right bottom)
		)
	)
	(label "GTY_224_TX1_P"
		(at 110.49 85.09 0)
		(effects
			(font
				(size 1.27 1.27)
			)
			(justify left bottom)
		)
	)
	(label "PCIE.TXD7_P"
		(at 163.83 74.93 180)
		(effects
			(font
				(size 1.27 1.27)
			)
			(justify right bottom)
		)
	)
	(label "HDMI_FPGA.TX_CLK_N"
		(at 298.45 81.28 180)
		(effects
			(font
				(size 1.27 1.27)
			)
			(justify right bottom)
		)
	)
	(label "PCIE.RXD2_N"
		(at 163.83 186.69 180)
		(effects
			(font
				(size 1.27 1.27)
			)
			(justify right bottom)
		)
	)
	(label "PCIE.RXD1_N"
		(at 163.83 193.04 180)
		(effects
			(font
				(size 1.27 1.27)
			)
			(justify right bottom)
		)
	)
	(label "PCIE.TXD2_P"
		(at 163.83 125.73 180)
		(effects
			(font
				(size 1.27 1.27)
			)
			(justify right bottom)
		)
	)
	(label "HDMI_IN.D2_P"
		(at 358.14 104.14 180)
		(effects
			(font
				(size 1.27 1.27)
			)
			(justify right bottom)
		)
	)
	(label "HDMI_IN.D1_N"
		(at 358.14 97.79 180)
		(effects
			(font
				(size 1.27 1.27)
			)
			(justify right bottom)
		)
	)
	(label "PCIE.RXD2_P"
		(at 163.83 184.15 180)
		(effects
			(font
				(size 1.27 1.27)
			)
			(justify right bottom)
		)
	)
	(label "HDMI_FPGA.RX1_N"
		(at 294.64 93.98 180)
		(effects
			(font
				(size 1.27 1.27)
			)
			(justify right bottom)
		)
	)
	(label "PCIE.TXD0_N"
		(at 163.83 147.32 180)
		(effects
			(font
				(size 1.27 1.27)
			)
			(justify right bottom)
		)
	)
	(label "GTY_224_RX0_N"
		(at 92.71 102.87 180)
		(effects
			(font
				(size 1.27 1.27)
			)
			(justify right bottom)
		)
	)
	(label "GTY_225_TX1_P"
		(at 92.71 160.02 180)
		(effects
			(font
				(size 1.27 1.27)
			)
			(justify right bottom)
		)
	)
	(label "GTY_225_RX3_P"
		(at 110.49 196.85 0)
		(effects
			(font
				(size 1.27 1.27)
			)
			(justify left bottom)
		)
	)
	(label "HDMI_IN.CLK_P"
		(at 358.14 119.38 180)
		(effects
			(font
				(size 1.27 1.27)
			)
			(justify right bottom)
		)
	)
	(label "PCIE.RXD3_N"
		(at 163.83 180.34 180)
		(effects
			(font
				(size 1.27 1.27)
			)
			(justify right bottom)
		)
	)
	(label "GTY_225_TX3_P"
		(at 110.49 144.78 0)
		(effects
			(font
				(size 1.27 1.27)
			)
			(justify left bottom)
		)
	)
	(label "HDMI_IN.CLK_N"
		(at 358.14 121.92 180)
		(effects
			(font
				(size 1.27 1.27)
			)
			(justify right bottom)
		)
	)
	(label "HDMI_REC_CLK_C_N"
		(at 285.75 201.93 0)
		(effects
			(font
				(size 1.27 1.27)
			)
			(justify left bottom)
		)
	)
	(label "HDMI_OUT.CLK_P"
		(at 358.14 78.74 180)
		(effects
			(font
				(size 1.27 1.27)
			)
			(justify right bottom)
		)
	)
	(label "GTY_225_TX2_P"
		(at 110.49 134.62 0)
		(effects
			(font
				(size 1.27 1.27)
			)
			(justify left bottom)
		)
	)
	(label "GTY_224_TX3_N"
		(at 92.71 95.25 180)
		(effects
			(font
				(size 1.27 1.27)
			)
			(justify right bottom)
		)
	)
	(label "HDMI_CTL.SDA"
		(at 292.1 217.17 0)
		(effects
			(font
				(size 1.27 1.27)
			)
			(justify left bottom)
		)
	)
	(label "HDMI_SI5319_CLK_N"
		(at 316.23 111.76 180)
		(effects
			(font
				(size 1.27 1.27)
			)
			(justify right bottom)
		)
	)
	(label "GTY_225_TX1_N"
		(at 110.49 128.27 0)
		(effects
			(font
				(size 1.27 1.27)
			)
			(justify left bottom)
		)
	)
	(label "GTY_224_TX0_P"
		(at 92.71 77.47 180)
		(effects
			(font
				(size 1.27 1.27)
			)
			(justify right bottom)
		)
	)
	(label "GTY_224_TX1_N"
		(at 110.49 87.63 0)
		(effects
			(font
				(size 1.27 1.27)
			)
			(justify left bottom)
		)
	)
	(label "GTY_224_TX3_P"
		(at 92.71 92.71 180)
		(effects
			(font
				(size 1.27 1.27)
			)
			(justify right bottom)
		)
	)
	(label "GTR_REFCLK0_N"
		(at 110.49 208.28 0)
		(effects
			(font
				(size 1.27 1.27)
			)
			(justify left bottom)
		)
	)
	(label "GTY_225_TX0_P"
		(at 92.71 154.94 180)
		(effects
			(font
				(size 1.27 1.27)
			)
			(justify right bottom)
		)
	)
	(label "GTY_225_RX2_N"
		(at 110.49 193.04 0)
		(effects
			(font
				(size 1.27 1.27)
			)
			(justify left bottom)
		)
	)
	(label "HDMI_OUT.D1_P"
		(at 358.14 62.23 180)
		(effects
			(font
				(size 1.27 1.27)
			)
			(justify right bottom)
		)
	)
	(label "HDMI_FPGA.TX_CLK_P"
		(at 298.45 78.74 180)
		(effects
			(font
				(size 1.27 1.27)
			)
			(justify right bottom)
		)
	)
	(label "GTY_225_RX0_P"
		(at 92.71 177.8 180)
		(effects
			(font
				(size 1.27 1.27)
			)
			(justify right bottom)
		)
	)
	(label "PCIE.RXD7_P"
		(at 163.83 151.13 180)
		(effects
			(font
				(size 1.27 1.27)
			)
			(justify right bottom)
		)
	)
	(label "HDMI_SI5319_CLK_N"
		(at 394.97 201.93 180)
		(effects
			(font
				(size 1.27 1.27)
			)
			(justify right bottom)
		)
	)
	(label "HDMI_REC_CLK_C_P"
		(at 285.75 199.39 0)
		(effects
			(font
				(size 1.27 1.27)
			)
			(justify left bottom)
		)
	)
	(label "GTY_224_RX0_P"
		(at 92.71 100.33 180)
		(effects
			(font
				(size 1.27 1.27)
			)
			(justify right bottom)
		)
	)
	(label "PCIE.TXD5_P"
		(at 163.83 95.25 180)
		(effects
			(font
				(size 1.27 1.27)
			)
			(justify right bottom)
		)
	)
	(label "GTY_224_TX1_N"
		(at 92.71 85.09 180)
		(effects
			(font
				(size 1.27 1.27)
			)
			(justify right bottom)
		)
	)
	(label "GTY_224_TX3_P"
		(at 110.49 104.14 0)
		(effects
			(font
				(size 1.27 1.27)
			)
			(justify left bottom)
		)
	)
	(label "PCIE.CLK_N"
		(at 163.83 208.28 180)
		(effects
			(font
				(size 1.27 1.27)
			)
			(justify right bottom)
		)
	)
	(label "PCIE.RXD4_N"
		(at 163.83 172.72 180)
		(effects
			(font
				(size 1.27 1.27)
			)
			(justify right bottom)
		)
	)
	(label "PCIE.RXD4_P"
		(at 163.83 170.18 180)
		(effects
			(font
				(size 1.27 1.27)
			)
			(justify right bottom)
		)
	)
	(label "GTY_224_TX0_N"
		(at 92.71 80.01 180)
		(effects
			(font
				(size 1.27 1.27)
			)
			(justify right bottom)
		)
	)
	(label "GTY_224_RX2_P"
		(at 92.71 110.49 180)
		(effects
			(font
				(size 1.27 1.27)
			)
			(justify right bottom)
		)
	)
	(label "GTY_224_RX1_P"
		(at 92.71 105.41 180)
		(effects
			(font
				(size 1.27 1.27)
			)
			(justify right bottom)
		)
	)
	(label "HDMI_FPGA.RX1_P"
		(at 294.64 91.44 180)
		(effects
			(font
				(size 1.27 1.27)
			)
			(justify right bottom)
		)
	)
	(label "HDMI_CTL.SCL"
		(at 292.1 219.71 0)
		(effects
			(font
				(size 1.27 1.27)
			)
			(justify left bottom)
		)
	)
	(label "GTY_224_RX3_N"
		(at 92.71 118.11 180)
		(effects
			(font
				(size 1.27 1.27)
			)
			(justify right bottom)
		)
	)
	(label "PCIE.TXD4_P"
		(at 163.83 104.14 180)
		(effects
			(font
				(size 1.27 1.27)
			)
			(justify right bottom)
		)
	)
	(label "GTY_225_TX3_N"
		(at 110.49 147.32 0)
		(effects
			(font
				(size 1.27 1.27)
			)
			(justify left bottom)
		)
	)
	(label "HDMI_SI5319_CLK_P"
		(at 394.97 199.39 180)
		(effects
			(font
				(size 1.27 1.27)
			)
			(justify right bottom)
		)
	)
	(label "GTY_224_RX1_P"
		(at 110.49 157.48 0)
		(effects
			(font
				(size 1.27 1.27)
			)
			(justify left bottom)
		)
	)
	(label "GTY_225_RX2_P"
		(at 92.71 187.96 180)
		(effects
			(font
				(size 1.27 1.27)
			)
			(justify right bottom)
		)
	)
	(label "GTY_225_TX0_P"
		(at 110.49 115.57 0)
		(effects
			(font
				(size 1.27 1.27)
			)
			(justify left bottom)
		)
	)
	(label "HDMI_OUT.D1_N"
		(at 358.14 64.77 180)
		(effects
			(font
				(size 1.27 1.27)
			)
			(justify right bottom)
		)
	)
	(label "GTY_224_RX2_N"
		(at 92.71 113.03 180)
		(effects
			(font
				(size 1.27 1.27)
			)
			(justify right bottom)
		)
	)
	(label "PCIE.TXD3_N"
		(at 163.83 118.11 180)
		(effects
			(font
				(size 1.27 1.27)
			)
			(justify right bottom)
		)
	)
	(label "HDMI_SI5319_C_CLK_P"
		(at 358.14 199.39 180)
		(effects
			(font
				(size 1.27 1.27)
			)
			(justify right bottom)
		)
	)
	(label "GTY_225_RX1_P"
		(at 110.49 184.15 0)
		(effects
			(font
				(size 1.27 1.27)
			)
			(justify left bottom)
		)
	)
	(label "PCIE.RXD7_N"
		(at 163.83 153.67 180)
		(effects
			(font
				(size 1.27 1.27)
			)
			(justify right bottom)
		)
	)
	(label "GTY_224_TX0_N"
		(at 110.49 77.47 0)
		(effects
			(font
				(size 1.27 1.27)
			)
			(justify left bottom)
		)
	)
	(label "GTY_224_TX2_N"
		(at 110.49 97.79 0)
		(effects
			(font
				(size 1.27 1.27)
			)
			(justify left bottom)
		)
	)
	(label "GTR_REFCLK0_P"
		(at 110.49 205.74 0)
		(effects
			(font
				(size 1.27 1.27)
			)
			(justify left bottom)
		)
	)
	(label "PCIE.RXD1_P"
		(at 163.83 190.5 180)
		(effects
			(font
				(size 1.27 1.27)
			)
			(justify right bottom)
		)
	)
	(label "GTY_224_TX3_N"
		(at 110.49 106.68 0)
		(effects
			(font
				(size 1.27 1.27)
			)
			(justify left bottom)
		)
	)
	(label "HDMI_FPGA.RX2_N"
		(at 294.64 99.06 180)
		(effects
			(font
				(size 1.27 1.27)
			)
			(justify right bottom)
		)
	)
	(label "HDMI_FPGA.TX1_P"
		(at 294.64 68.58 180)
		(effects
			(font
				(size 1.27 1.27)
			)
			(justify right bottom)
		)
	)
	(label "GTY_225_RX3_P"
		(at 92.71 193.04 180)
		(effects
			(font
				(size 1.27 1.27)
			)
			(justify right bottom)
		)
	)
	(label "PCIE.TXD1_P"
		(at 163.83 134.62 180)
		(effects
			(font
				(size 1.27 1.27)
			)
			(justify right bottom)
		)
	)
	(label "HDMI_OUT.D2_N"
		(at 358.14 72.39 180)
		(effects
			(font
				(size 1.27 1.27)
			)
			(justify right bottom)
		)
	)
	(label "PCIE.TXD4_N"
		(at 163.83 106.68 180)
		(effects
			(font
				(size 1.27 1.27)
			)
			(justify right bottom)
		)
	)
	(label "HDMI_IN.D0_P"
		(at 358.14 86.36 180)
		(effects
			(font
				(size 1.27 1.27)
			)
			(justify right bottom)
		)
	)
	(label "GTY_224_TX2_P"
		(at 92.71 87.63 180)
		(effects
			(font
				(size 1.27 1.27)
			)
			(justify right bottom)
		)
	)
	(label "GTY_224_RX3_P"
		(at 110.49 170.18 0)
		(effects
			(font
				(size 1.27 1.27)
			)
			(justify left bottom)
		)
	)
	(label "GTY_225_TX2_N"
		(at 92.71 167.64 180)
		(effects
			(font
				(size 1.27 1.27)
			)
			(justify right bottom)
		)
	)
	(label "GTY_225_TX3_N"
		(at 92.71 172.72 180)
		(effects
			(font
				(size 1.27 1.27)
			)
			(justify right bottom)
		)
	)
	(label "GTY_225_TX0_N"
		(at 110.49 118.11 0)
		(effects
			(font
				(size 1.27 1.27)
			)
			(justify left bottom)
		)
	)
	(label "HDMI_IN.D2_N"
		(at 358.14 106.68 180)
		(effects
			(font
				(size 1.27 1.27)
			)
			(justify right bottom)
		)
	)
	(label "GTY_225_RX0_P"
		(at 110.49 177.8 0)
		(effects
			(font
				(size 1.27 1.27)
			)
			(justify left bottom)
		)
	)
	(label "GTY_225_TX1_P"
		(at 110.49 125.73 0)
		(effects
			(font
				(size 1.27 1.27)
			)
			(justify left bottom)
		)
	)
	(label "GTY_224_RX0_P"
		(at 110.49 151.13 0)
		(effects
			(font
				(size 1.27 1.27)
			)
			(justify left bottom)
		)
	)
	(label "HDMI_SI5319_C_CLK_N"
		(at 358.14 201.93 180)
		(effects
			(font
				(size 1.27 1.27)
			)
			(justify right bottom)
		)
	)
	(label "HDMI_FPGA.TX2_P"
		(at 294.64 73.66 180)
		(effects
			(font
				(size 1.27 1.27)
			)
			(justify right bottom)
		)
	)
	(label "GTY_225_TX1_N"
		(at 92.71 162.56 180)
		(effects
			(font
				(size 1.27 1.27)
			)
			(justify right bottom)
		)
	)
	(label "PCIE.TXD6_P"
		(at 163.83 85.09 180)
		(effects
			(font
				(size 1.27 1.27)
			)
			(justify right bottom)
		)
	)
	(label "GTY_225_RX0_N"
		(at 110.49 180.34 0)
		(effects
			(font
				(size 1.27 1.27)
			)
			(justify left bottom)
		)
	)
	(label "HDMI_FPGA.TX0_P"
		(at 294.64 63.5 180)
		(effects
			(font
				(size 1.27 1.27)
			)
			(justify right bottom)
		)
	)
	(label "HDMI_FPGA.TX1_N"
		(at 294.64 71.12 180)
		(effects
			(font
				(size 1.27 1.27)
			)
			(justify right bottom)
		)
	)
	(label "XB"
		(at 307.34 191.77 0)
		(effects
			(font
				(size 1.27 1.27)
			)
			(justify left bottom)
		)
	)
	(label "GTY_224_TX0_P"
		(at 110.49 74.93 0)
		(effects
			(font
				(size 1.27 1.27)
			)
			(justify left bottom)
		)
	)
	(label "GTY_224_RX1_N"
		(at 92.71 107.95 180)
		(effects
			(font
				(size 1.27 1.27)
			)
			(justify right bottom)
		)
	)
	(label "PCIE.RXD0_P"
		(at 163.83 196.85 180)
		(effects
			(font
				(size 1.27 1.27)
			)
			(justify right bottom)
		)
	)
	(label "GTY_225_TX2_N"
		(at 110.49 137.16 0)
		(effects
			(font
				(size 1.27 1.27)
			)
			(justify left bottom)
		)
	)
	(label "HDMI_SI5319_CLK_P"
		(at 316.23 109.22 180)
		(effects
			(font
				(size 1.27 1.27)
			)
			(justify right bottom)
		)
	)
	(label "GTY_225_RX1_N"
		(at 92.71 185.42 180)
		(effects
			(font
				(size 1.27 1.27)
			)
			(justify right bottom)
		)
	)
	(label "GTY_225_RX3_N"
		(at 110.49 199.39 0)
		(effects
			(font
				(size 1.27 1.27)
			)
			(justify left bottom)
		)
	)
	(label "PCIE.TXD3_P"
		(at 163.83 115.57 180)
		(effects
			(font
				(size 1.27 1.27)
			)
			(justify right bottom)
		)
	)
	(label "PCIE.RXD3_P"
		(at 163.83 177.8 180)
		(effects
			(font
				(size 1.27 1.27)
			)
			(justify right bottom)
		)
	)
	(label "HDMI_IN.D1_P"
		(at 358.14 95.25 180)
		(effects
			(font
				(size 1.27 1.27)
			)
			(justify right bottom)
		)
	)
	(label "GTY_224_RX3_P"
		(at 92.71 115.57 180)
		(effects
			(font
				(size 1.27 1.27)
			)
			(justify right bottom)
		)
	)
	(label "GTY_225_RX3_N"
		(at 92.71 195.58 180)
		(effects
			(font
				(size 1.27 1.27)
			)
			(justify right bottom)
		)
	)
	(label "PCIE.RXD6_P"
		(at 163.83 157.48 180)
		(effects
			(font
				(size 1.27 1.27)
			)
			(justify right bottom)
		)
	)
	(label "XA"
		(at 307.34 189.23 0)
		(effects
			(font
				(size 1.27 1.27)
			)
			(justify left bottom)
		)
	)
	(label "PCIE.CLK_P"
		(at 163.83 205.74 180)
		(effects
			(font
				(size 1.27 1.27)
			)
			(justify right bottom)
		)
	)
	(label "GTR_REFCLK0_P"
		(at 92.71 123.19 180)
		(effects
			(font
				(size 1.27 1.27)
			)
			(justify right bottom)
		)
	)
	(label "HDMI_OUT.D0_P"
		(at 358.14 54.61 180)
		(effects
			(font
				(size 1.27 1.27)
			)
			(justify right bottom)
		)
	)
	(label "GTY_224_RX0_N"
		(at 110.49 153.67 0)
		(effects
			(font
				(size 1.27 1.27)
			)
			(justify left bottom)
		)
	)
	(label "PCIE.TXD1_N"
		(at 163.83 137.16 180)
		(effects
			(font
				(size 1.27 1.27)
			)
			(justify right bottom)
		)
	)
	(label "GTY_225_TX3_P"
		(at 92.71 170.18 180)
		(effects
			(font
				(size 1.27 1.27)
			)
			(justify right bottom)
		)
	)
	(label "HDMI_FPGA.RX0_N"
		(at 294.64 88.9 180)
		(effects
			(font
				(size 1.27 1.27)
			)
			(justify right bottom)
		)
	)
	(label "PCIE.TXD6_N"
		(at 163.83 87.63 180)
		(effects
			(font
				(size 1.27 1.27)
			)
			(justify right bottom)
		)
	)
	(label "PCIE.RXD5_N"
		(at 163.83 166.37 180)
		(effects
			(font
				(size 1.27 1.27)
			)
			(justify right bottom)
		)
	)
	(label "HDMI_IN_CLK_C_P"
		(at 278.13 114.3 0)
		(effects
			(font
				(size 1.27 1.27)
			)
			(justify left bottom)
		)
	)
	(label "GTY_225_RX0_N"
		(at 92.71 180.34 180)
		(effects
			(font
				(size 1.27 1.27)
			)
			(justify right bottom)
		)
	)
	(label "HDMI_FPGA.TX0_N"
		(at 294.64 66.04 180)
		(effects
			(font
				(size 1.27 1.27)
			)
			(justify right bottom)
		)
	)
	(label "PCIE.TXD0_P"
		(at 163.83 144.78 180)
		(effects
			(font
				(size 1.27 1.27)
			)
			(justify right bottom)
		)
	)
	(label "HDMI_OUT.D2_P"
		(at 358.14 69.85 180)
		(effects
			(font
				(size 1.27 1.27)
			)
			(justify right bottom)
		)
	)
	(label "GTY_224_RX1_N"
		(at 110.49 160.02 0)
		(effects
			(font
				(size 1.27 1.27)
			)
			(justify left bottom)
		)
	)
	(label "HDMI_FPGA.RX2_P"
		(at 294.64 96.52 180)
		(effects
			(font
				(size 1.27 1.27)
			)
			(justify right bottom)
		)
	)
	(label "HDMI_IN_CLK_C_N"
		(at 278.13 116.84 0)
		(effects
			(font
				(size 1.27 1.27)
			)
			(justify left bottom)
		)
	)
	(label "GTY_224_TX2_N"
		(at 92.71 90.17 180)
		(effects
			(font
				(size 1.27 1.27)
			)
			(justify right bottom)
		)
	)
	(label "GTY_225_RX1_P"
		(at 92.71 182.88 180)
		(effects
			(font
				(size 1.27 1.27)
			)
			(justify right bottom)
		)
	)
	(label "GTY_225_TX0_N"
		(at 92.71 157.48 180)
		(effects
			(font
				(size 1.27 1.27)
			)
			(justify right bottom)
		)
	)
	(label "GTY_224_RX2_P"
		(at 110.49 163.83 0)
		(effects
			(font
				(size 1.27 1.27)
			)
			(justify left bottom)
		)
	)
	(label "HDMI_IN.D0_N"
		(at 358.14 88.9 180)
		(effects
			(font
				(size 1.27 1.27)
			)
			(justify right bottom)
		)
	)
	(label "GTY_225_RX2_N"
		(at 92.71 190.5 180)
		(effects
			(font
				(size 1.27 1.27)
			)
			(justify right bottom)
		)
	)
	(label "GTY_224_RX3_N"
		(at 110.49 172.72 0)
		(effects
			(font
				(size 1.27 1.27)
			)
			(justify left bottom)
		)
	)
	(label "GTR_REFCLK0_N"
		(at 92.71 125.73 180)
		(effects
			(font
				(size 1.27 1.27)
			)
			(justify right bottom)
		)
	)
	(label "PCIE.RXD0_N"
		(at 163.83 199.39 180)
		(effects
			(font
				(size 1.27 1.27)
			)
			(justify right bottom)
		)
	)
	(label "PCIE.RXD6_N"
		(at 163.83 160.02 180)
		(effects
			(font
				(size 1.27 1.27)
			)
			(justify right bottom)
		)
	)
	(label "GTY_224_RX2_N"
		(at 110.49 166.37 0)
		(effects
			(font
				(size 1.27 1.27)
			)
			(justify left bottom)
		)
	)
	(label "HDMI_OUT.CLK_N"
		(at 358.14 81.28 180)
		(effects
			(font
				(size 1.27 1.27)
			)
			(justify right bottom)
		)
	)
	(label "PCIE.TXD7_N"
		(at 163.83 77.47 180)
		(effects
			(font
				(size 1.27 1.27)
			)
			(justify right bottom)
		)
	)
	(label "HDMI_FPGA.RX0_P"
		(at 294.64 86.36 180)
		(effects
			(font
				(size 1.27 1.27)
			)
			(justify right bottom)
		)
	)
	(label "PCIE.RXD5_P"
		(at 163.83 163.83 180)
		(effects
			(font
				(size 1.27 1.27)
			)
			(justify right bottom)
		)
	)
	(label "GTY_224_TX2_P"
		(at 110.49 95.25 0)
		(effects
			(font
				(size 1.27 1.27)
			)
			(justify left bottom)
		)
	)
	(label "HDMI_OUT.D0_N"
		(at 358.14 57.15 180)
		(effects
			(font
				(size 1.27 1.27)
			)
			(justify right bottom)
		)
	)
	(label "HDMI_FPGA.TX2_N"
		(at 294.64 76.2 180)
		(effects
			(font
				(size 1.27 1.27)
			)
			(justify right bottom)
		)
	)
	(label "GTY_224_TX1_P"
		(at 92.71 82.55 180)
		(effects
			(font
				(size 1.27 1.27)
			)
			(justify right bottom)
		)
	)
	(global_label "~{SI_5319_RST}"
		(shape input)
		(at 279.4 181.61 180)
		(fields_autoplaced yes)
		(effects
			(font
				(size 1.27 1.27)
			)
			(justify right)
		)
		(property "Intersheetrefs" "${INTERSHEET_REFS}"
			(at 265.0344 181.61 0)
			(effects
				(font
					(size 1.27 1.27)
				)
				(justify right)
			)
		)
	)
	(global_label "HDMI_REC_CLK_P"
		(shape input)
		(at 259.08 199.39 180)
		(fields_autoplaced yes)
		(effects
			(font
				(size 1.27 1.27)
			)
			(justify right)
		)
		(property "Intersheetrefs" "${INTERSHEET_REFS}"
			(at 240.0082 199.39 0)
			(effects
				(font
					(size 1.27 1.27)
				)
				(justify right)
			)
		)
	)
	(global_label "LOL"
		(shape output)
		(at 339.09 234.95 0)
		(fields_autoplaced yes)
		(effects
			(font
				(size 1.27 1.27)
			)
			(justify left)
		)
		(property "Intersheetrefs" "${INTERSHEET_REFS}"
			(at 344.8077 234.95 0)
			(effects
				(font
					(size 1.27 1.27)
				)
				(justify left)
			)
		)
	)
	(global_label "HDMI_REC_CLK_N"
		(shape input)
		(at 259.08 201.93 180)
		(fields_autoplaced yes)
		(effects
			(font
				(size 1.27 1.27)
			)
			(justify right)
		)
		(property "Intersheetrefs" "${INTERSHEET_REFS}"
			(at 239.9477 201.93 0)
			(effects
				(font
					(size 1.27 1.27)
				)
				(justify right)
			)
		)
	)
	(global_label "INT_CB"
		(shape output)
		(at 339.09 232.41 0)
		(fields_autoplaced yes)
		(effects
			(font
				(size 1.27 1.27)
			)
			(justify left)
		)
		(property "Intersheetrefs" "${INTERSHEET_REFS}"
			(at 347.8315 232.41 0)
			(effects
				(font
					(size 1.27 1.27)
				)
				(justify left)
			)
		)
	)
	(hierarchical_label "PCIE{PCIe_x8}"
		(shape bidirectional)
		(at 170.18 64.77 0)
		(effects
			(font
				(size 1.27 1.27)
			)
			(justify left)
		)
	)
	(hierarchical_label "HDMI_CTL{I^{2}C}"
		(shape bidirectional)
		(at 285.75 210.82 180)
		(effects
			(font
				(size 1.27 1.27)
			)
			(justify right)
		)
	)
	(hierarchical_label "HDMI_IN{TMDS}"
		(shape bidirectional)
		(at 365.76 129.54 0)
		(effects
			(font
				(size 1.27 1.27)
			)
			(justify left)
		)
	)
	(hierarchical_label "HDMI_OUT{TMDS}"
		(shape bidirectional)
		(at 365.76 45.72 0)
		(effects
			(font
				(size 1.27 1.27)
			)
			(justify left)
		)
	)
	(symbol
		(lib_id "antmicroCapacitors0402:C_100n_0402")
		(at 325.12 104.14 180)
		(unit 1)
		(exclude_from_sim no)
		(in_bom yes)
		(on_board yes)
		(dnp no)
		(property "Reference" "C303"
			(at 318.77 102.87 0)
			(effects
				(font
					(size 1.27 1.27)
				)
			)
		)
		(property "Value" "C_100n_0402"
			(at 304.8 93.98 0)
			(effects
				(font
					(size 1.27 1.27)
					(thickness 0.15)
				)
				(justify left bottom)
				(hide yes)
			)
		)
		(property "Footprint" "antmicro-footprints:C_0402_1005Metric"
			(at 304.8 91.44 0)
			(effects
				(font
					(size 1.27 1.27)
					(thickness 0.15)
				)
				(justify left bottom)
				(hide yes)
			)
		)
		(property "Datasheet" "https://www.murata.com/products/productdetail?partno=GRM155R61H104KE14%23"
			(at 304.8 88.9 0)
			(effects
				(font
					(size 1.27 1.27)
					(thickness 0.15)
				)
				(justify left bottom)
				(hide yes)
			)
		)
		(property "Description" ""
			(at 325.12 104.14 0)
			(effects
				(font
					(size 1.27 1.27)
				)
				(hide yes)
			)
		)
		(property "Manufacturer" "Murata"
			(at 304.8 83.82 0)
			(effects
				(font
					(size 1.27 1.27)
					(thickness 0.15)
				)
				(justify left bottom)
				(hide yes)
			)
		)
		(property "MPN" "GRM155R61H104KE14D"
			(at 304.8 86.36 0)
			(effects
				(font
					(size 1.27 1.27)
					(thickness 0.15)
				)
				(justify left bottom)
				(hide yes)
			)
		)
		(property "Val" "100n"
			(at 319.405 105.41 0)
			(effects
				(font
					(size 1.27 1.27)
					(thickness 0.15)
				)
			)
		)
		(property "License" "Apache-2.0"
			(at 304.8 81.28 0)
			(effects
				(font
					(size 1.27 1.27)
					(thickness 0.15)
				)
				(justify left bottom)
				(hide yes)
			)
		)
		(property "Author" "Antmicro"
			(at 304.8 78.74 0)
			(effects
				(font
					(size 1.27 1.27)
					(thickness 0.15)
				)
				(justify left bottom)
				(hide yes)
			)
		)
		(property "Voltage" "50V"
			(at 304.8 76.2 0)
			(effects
				(font
					(size 1.27 1.27)
				)
				(justify left bottom)
				(hide yes)
			)
		)
		(property "Dielectric" "X5R"
			(at 304.8 73.66 0)
			(effects
				(font
					(size 1.27 1.27)
				)
				(justify left bottom)
				(hide yes)
			)
		)
		(pin "1"
		)
		(pin "2"
		)
		(instances
			(project "data-center-rdimm-ddr5-tester"
				(path ""
					(reference "C303")
					(unit 1)
				)
			)
		)
	)
	(symbol
		(lib_id "antmicroCapacitors0402:C_100n_0402")
		(at 325.12 95.25 0)
		(mirror y)
		(unit 1)
		(exclude_from_sim no)
		(in_bom yes)
		(on_board yes)
		(dnp no)
		(property "Reference" "C305"
			(at 318.77 93.98 0)
			(effects
				(font
					(size 1.27 1.27)
				)
			)
		)
		(property "Value" "C_100n_0402"
			(at 304.8 105.41 0)
			(effects
				(font
					(size 1.27 1.27)
					(thickness 0.15)
				)
				(justify left bottom)
				(hide yes)
			)
		)
		(property "Footprint" "antmicro-footprints:C_0402_1005Metric"
			(at 304.8 107.95 0)
			(effects
				(font
					(size 1.27 1.27)
					(thickness 0.15)
				)
				(justify left bottom)
				(hide yes)
			)
		)
		(property "Datasheet" "https://www.murata.com/products/productdetail?partno=GRM155R61H104KE14%23"
			(at 304.8 110.49 0)
			(effects
				(font
					(size 1.27 1.27)
					(thickness 0.15)
				)
				(justify left bottom)
				(hide yes)
			)
		)
		(property "Description" ""
			(at 325.12 95.25 0)
			(effects
				(font
					(size 1.27 1.27)
				)
				(hide yes)
			)
		)
		(property "Manufacturer" "Murata"
			(at 304.8 115.57 0)
			(effects
				(font
					(size 1.27 1.27)
					(thickness 0.15)
				)
				(justify left bottom)
				(hide yes)
			)
		)
		(property "MPN" "GRM155R61H104KE14D"
			(at 304.8 113.03 0)
			(effects
				(font
					(size 1.27 1.27)
					(thickness 0.15)
				)
				(justify left bottom)
				(hide yes)
			)
		)
		(property "Val" "100n"
			(at 318.77 96.52 0)
			(effects
				(font
					(size 1.27 1.27)
					(thickness 0.15)
				)
			)
		)
		(property "License" "Apache-2.0"
			(at 304.8 118.11 0)
			(effects
				(font
					(size 1.27 1.27)
					(thickness 0.15)
				)
				(justify left bottom)
				(hide yes)
			)
		)
		(property "Author" "Antmicro"
			(at 304.8 120.65 0)
			(effects
				(font
					(size 1.27 1.27)
					(thickness 0.15)
				)
				(justify left bottom)
				(hide yes)
			)
		)
		(property "Voltage" "50V"
			(at 304.8 123.19 0)
			(effects
				(font
					(size 1.27 1.27)
				)
				(justify left bottom)
				(hide yes)
			)
		)
		(property "Dielectric" "X5R"
			(at 304.8 125.73 0)
			(effects
				(font
					(size 1.27 1.27)
				)
				(justify left bottom)
				(hide yes)
			)
		)
		(pin "1"
		)
		(pin "2"
		)
		(instances
			(project "data-center-rdimm-ddr5-tester"
				(path ""
					(reference "C305")
					(unit 1)
				)
			)
		)
	)
	(symbol
		(lib_id "antmicropower:+3V3")
		(at 223.52 162.56 0)
		(mirror y)
		(unit 1)
		(exclude_from_sim no)
		(in_bom yes)
		(on_board yes)
		(dnp no)
		(fields_autoplaced yes)
		(property "Reference" "#PWR0468"
			(at 208.28 162.56 0)
			(effects
				(font
					(size 1.27 1.27)
					(thickness 0.15)
				)
				(justify left bottom)
				(hide yes)
			)
		)
		(property "Value" "+3V3"
			(at 223.52 157.48 0)
			(effects
				(font
					(size 1.27 1.27)
					(thickness 0.15)
				)
			)
		)
		(property "Footprint" ""
			(at 208.28 170.18 0)
			(effects
				(font
					(size 1.27 1.27)
					(thickness 0.15)
				)
				(justify left bottom)
				(hide yes)
			)
		)
		(property "Datasheet" ""
			(at 208.28 172.72 0)
			(effects
				(font
					(size 1.27 1.27)
					(thickness 0.15)
				)
				(justify left bottom)
				(hide yes)
			)
		)
		(property "Description" ""
			(at 223.52 162.56 0)
			(effects
				(font
					(size 1.27 1.27)
				)
				(hide yes)
			)
		)
		(property "Author" "Antmicro"
			(at 208.28 165.1 0)
			(effects
				(font
					(size 1.27 1.27)
					(thickness 0.15)
				)
				(justify left bottom)
				(hide yes)
			)
		)
		(property "License" "Apache-2.0"
			(at 208.28 167.64 0)
			(effects
				(font
					(size 1.27 1.27)
					(thickness 0.15)
				)
				(justify left bottom)
				(hide yes)
			)
		)
		(pin "1"
		)
		(instances
			(project "data-center-rdimm-ddr5-tester"
				(path ""
					(reference "#PWR0468")
					(unit 1)
				)
			)
		)
	)
	(symbol
		(lib_id "antmicroCapacitors0402:C_100n_0402")
		(at 274.32 196.85 0)
		(unit 1)
		(exclude_from_sim no)
		(in_bom yes)
		(on_board yes)
		(dnp no)
		(property "Reference" "C315"
			(at 273.05 195.58 0)
			(effects
				(font
					(size 1.27 1.27)
					(thickness 0.15)
				)
			)
		)
		(property "Value" "C_100n_0402"
			(at 294.64 207.01 0)
			(effects
				(font
					(size 1.27 1.27)
					(thickness 0.15)
				)
				(justify left bottom)
				(hide yes)
			)
		)
		(property "Footprint" "antmicro-footprints:C_0402_1005Metric"
			(at 294.64 209.55 0)
			(effects
				(font
					(size 1.27 1.27)
					(thickness 0.15)
				)
				(justify left bottom)
				(hide yes)
			)
		)
		(property "Datasheet" "https://www.murata.com/products/productdetail?partno=GRM155R61H104KE14%23"
			(at 294.64 212.09 0)
			(effects
				(font
					(size 1.27 1.27)
					(thickness 0.15)
				)
				(justify left bottom)
				(hide yes)
			)
		)
		(property "Description" ""
			(at 274.32 196.85 0)
			(effects
				(font
					(size 1.27 1.27)
				)
				(hide yes)
			)
		)
		(property "MPN" "GRM155R61H104KE14D"
			(at 294.64 214.63 0)
			(effects
				(font
					(size 1.27 1.27)
					(thickness 0.15)
				)
				(justify left bottom)
				(hide yes)
			)
		)
		(property "Manufacturer" "Murata"
			(at 294.64 217.17 0)
			(effects
				(font
					(size 1.27 1.27)
					(thickness 0.15)
				)
				(justify left bottom)
				(hide yes)
			)
		)
		(property "License" "Apache-2.0"
			(at 294.64 219.71 0)
			(effects
				(font
					(size 1.27 1.27)
					(thickness 0.15)
				)
				(justify left bottom)
				(hide yes)
			)
		)
		(property "Author" "Antmicro"
			(at 294.64 222.25 0)
			(effects
				(font
					(size 1.27 1.27)
					(thickness 0.15)
				)
				(justify left bottom)
				(hide yes)
			)
		)
		(property "Val" "100n"
			(at 280.67 195.58 0)
			(effects
				(font
					(size 1.27 1.27)
					(thickness 0.15)
				)
			)
		)
		(property "Voltage" "50V"
			(at 294.64 224.79 0)
			(effects
				(font
					(size 1.27 1.27)
				)
				(justify left bottom)
				(hide yes)
			)
		)
		(property "Dielectric" "X5R"
			(at 294.64 227.33 0)
			(effects
				(font
					(size 1.27 1.27)
				)
				(justify left bottom)
				(hide yes)
			)
		)
		(pin "1"
		)
		(pin "2"
		)
		(instances
			(project "data-center-rdimm-ddr5-tester"
				(path ""
					(reference "C315")
					(unit 1)
				)
			)
		)
	)
	(symbol
		(lib_id "antmicroCapacitors0402:C_100n_0402")
		(at 142.24 124.46 0)
		(mirror y)
		(unit 1)
		(exclude_from_sim no)
		(in_bom yes)
		(on_board yes)
		(dnp no)
		(property "Reference" "C227"
			(at 143.51 123.19 0)
			(effects
				(font
					(size 1.27 1.27)
				)
			)
		)
		(property "Value" "C_100n_0402"
			(at 121.92 134.62 0)
			(effects
				(font
					(size 1.27 1.27)
					(thickness 0.15)
				)
				(justify left bottom)
				(hide yes)
			)
		)
		(property "Footprint" "antmicro-footprints:C_0402_1005Metric"
			(at 121.92 137.16 0)
			(effects
				(font
					(size 1.27 1.27)
					(thickness 0.15)
				)
				(justify left bottom)
				(hide yes)
			)
		)
		(property "Datasheet" "https://www.murata.com/products/productdetail?partno=GRM155R61H104KE14%23"
			(at 121.92 139.7 0)
			(effects
				(font
					(size 1.27 1.27)
					(thickness 0.15)
				)
				(justify left bottom)
				(hide yes)
			)
		)
		(property "Description" ""
			(at 142.24 124.46 0)
			(effects
				(font
					(size 1.27 1.27)
				)
				(hide yes)
			)
		)
		(property "Manufacturer" "Murata"
			(at 121.92 144.78 0)
			(effects
				(font
					(size 1.27 1.27)
					(thickness 0.15)
				)
				(justify left bottom)
				(hide yes)
			)
		)
		(property "MPN" "GRM155R61H104KE14D"
			(at 121.92 142.24 0)
			(effects
				(font
					(size 1.27 1.27)
					(thickness 0.15)
				)
				(justify left bottom)
				(hide yes)
			)
		)
		(property "Val" "100n"
			(at 136.525 123.19 0)
			(effects
				(font
					(size 1.27 1.27)
					(thickness 0.15)
				)
			)
		)
		(property "License" "Apache-2.0"
			(at 121.92 147.32 0)
			(effects
				(font
					(size 1.27 1.27)
					(thickness 0.15)
				)
				(justify left bottom)
				(hide yes)
			)
		)
		(property "Author" "Antmicro"
			(at 121.92 149.86 0)
			(effects
				(font
					(size 1.27 1.27)
					(thickness 0.15)
				)
				(justify left bottom)
				(hide yes)
			)
		)
		(property "Voltage" "50V"
			(at 121.92 152.4 0)
			(effects
				(font
					(size 1.27 1.27)
				)
				(justify left bottom)
				(hide yes)
			)
		)
		(property "Dielectric" "X5R"
			(at 121.92 154.94 0)
			(effects
				(font
					(size 1.27 1.27)
				)
				(justify left bottom)
				(hide yes)
			)
		)
		(pin "1"
		)
		(pin "2"
		)
		(instances
			(project "data-center-rdimm-ddr5-tester"
				(path ""
					(reference "C227")
					(unit 1)
				)
			)
		)
	)
	(symbol
		(lib_id "antmicroCapacitors0402:C_100n_0402")
		(at 325.12 121.92 0)
		(mirror x)
		(unit 1)
		(exclude_from_sim no)
		(in_bom yes)
		(on_board yes)
		(dnp no)
		(property "Reference" "C291"
			(at 331.47 120.65 0)
			(effects
				(font
					(size 1.27 1.27)
				)
			)
		)
		(property "Value" "C_100n_0402"
			(at 345.44 111.76 0)
			(effects
				(font
					(size 1.27 1.27)
					(thickness 0.15)
				)
				(justify left bottom)
				(hide yes)
			)
		)
		(property "Footprint" "antmicro-footprints:C_0402_1005Metric"
			(at 345.44 109.22 0)
			(effects
				(font
					(size 1.27 1.27)
					(thickness 0.15)
				)
				(justify left bottom)
				(hide yes)
			)
		)
		(property "Datasheet" "https://www.murata.com/products/productdetail?partno=GRM155R61H104KE14%23"
			(at 345.44 106.68 0)
			(effects
				(font
					(size 1.27 1.27)
					(thickness 0.15)
				)
				(justify left bottom)
				(hide yes)
			)
		)
		(property "Description" ""
			(at 325.12 121.92 0)
			(effects
				(font
					(size 1.27 1.27)
				)
				(hide yes)
			)
		)
		(property "Manufacturer" "Murata"
			(at 345.44 101.6 0)
			(effects
				(font
					(size 1.27 1.27)
					(thickness 0.15)
				)
				(justify left bottom)
				(hide yes)
			)
		)
		(property "MPN" "GRM155R61H104KE14D"
			(at 345.44 104.14 0)
			(effects
				(font
					(size 1.27 1.27)
					(thickness 0.15)
				)
				(justify left bottom)
				(hide yes)
			)
		)
		(property "Val" "100n"
			(at 331.47 123.19 0)
			(effects
				(font
					(size 1.27 1.27)
					(thickness 0.15)
				)
			)
		)
		(property "License" "Apache-2.0"
			(at 345.44 99.06 0)
			(effects
				(font
					(size 1.27 1.27)
					(thickness 0.15)
				)
				(justify left bottom)
				(hide yes)
			)
		)
		(property "Author" "Antmicro"
			(at 345.44 96.52 0)
			(effects
				(font
					(size 1.27 1.27)
					(thickness 0.15)
				)
				(justify left bottom)
				(hide yes)
			)
		)
		(property "Voltage" "50V"
			(at 345.44 93.98 0)
			(effects
				(font
					(size 1.27 1.27)
				)
				(justify left bottom)
				(hide yes)
			)
		)
		(property "Dielectric" "X5R"
			(at 345.44 91.44 0)
			(effects
				(font
					(size 1.27 1.27)
				)
				(justify left bottom)
				(hide yes)
			)
		)
		(pin "1"
		)
		(pin "2"
		)
		(instances
			(project "data-center-rdimm-ddr5-tester"
				(path ""
					(reference "C291")
					(unit 1)
				)
			)
		)
	)
	(symbol
		(lib_id "antmicroCapacitors0402:C_100n_0402")
		(at 363.22 199.39 0)
		(mirror x)
		(unit 1)
		(exclude_from_sim no)
		(in_bom yes)
		(on_board yes)
		(dnp no)
		(property "Reference" "C309"
			(at 361.95 198.12 0)
			(effects
				(font
					(size 1.27 1.27)
				)
			)
		)
		(property "Value" "C_100n_0402"
			(at 383.54 189.23 0)
			(effects
				(font
					(size 1.27 1.27)
					(thickness 0.15)
				)
				(justify left bottom)
				(hide yes)
			)
		)
		(property "Footprint" "antmicro-footprints:C_0402_1005Metric"
			(at 383.54 186.69 0)
			(effects
				(font
					(size 1.27 1.27)
					(thickness 0.15)
				)
				(justify left bottom)
				(hide yes)
			)
		)
		(property "Datasheet" "https://www.murata.com/products/productdetail?partno=GRM155R61H104KE14%23"
			(at 383.54 184.15 0)
			(effects
				(font
					(size 1.27 1.27)
					(thickness 0.15)
				)
				(justify left bottom)
				(hide yes)
			)
		)
		(property "Description" ""
			(at 363.22 199.39 0)
			(effects
				(font
					(size 1.27 1.27)
				)
				(hide yes)
			)
		)
		(property "Manufacturer" "Murata"
			(at 383.54 179.07 0)
			(effects
				(font
					(size 1.27 1.27)
					(thickness 0.15)
				)
				(justify left bottom)
				(hide yes)
			)
		)
		(property "MPN" "GRM155R61H104KE14D"
			(at 383.54 181.61 0)
			(effects
				(font
					(size 1.27 1.27)
					(thickness 0.15)
				)
				(justify left bottom)
				(hide yes)
			)
		)
		(property "Val" "100n"
			(at 368.935 198.12 0)
			(effects
				(font
					(size 1.27 1.27)
					(thickness 0.15)
				)
			)
		)
		(property "License" "Apache-2.0"
			(at 383.54 176.53 0)
			(effects
				(font
					(size 1.27 1.27)
					(thickness 0.15)
				)
				(justify left bottom)
				(hide yes)
			)
		)
		(property "Author" "Antmicro"
			(at 383.54 173.99 0)
			(effects
				(font
					(size 1.27 1.27)
					(thickness 0.15)
				)
				(justify left bottom)
				(hide yes)
			)
		)
		(property "Voltage" "50V"
			(at 383.54 171.45 0)
			(effects
				(font
					(size 1.27 1.27)
				)
				(justify left bottom)
				(hide yes)
			)
		)
		(property "Dielectric" "X5R"
			(at 383.54 168.91 0)
			(effects
				(font
					(size 1.27 1.27)
				)
				(justify left bottom)
				(hide yes)
			)
		)
		(pin "1"
		)
		(pin "2"
		)
		(instances
			(project "data-center-rdimm-ddr5-tester"
				(path ""
					(reference "C309")
					(unit 1)
				)
			)
		)
	)
	(symbol
		(lib_id "antmicroFPGAChips:XCAU25P-2FFVB676I")
		(at 278.13 63.5 0)
		(mirror y)
		(unit 11)
		(exclude_from_sim no)
		(in_bom yes)
		(on_board yes)
		(dnp no)
		(property "Reference" "U34"
			(at 270.51 53.34 0)
			(effects
				(font
					(size 1.27 1.27)
					(thickness 0.15)
				)
			)
		)
		(property "Value" "XCAU25P-2FFVB676I"
			(at 214.63 68.58 0)
			(effects
				(font
					(size 1.27 1.27)
					(thickness 0.15)
				)
				(justify left bottom)
				(hide yes)
			)
		)
		(property "Footprint" "antmicro-footprints:BGA-676_27x27mm_Layout26x26_P1x1mm_FFVB676"
			(at 214.63 71.12 0)
			(effects
				(font
					(size 1.27 1.27)
					(thickness 0.15)
				)
				(justify left bottom)
				(hide yes)
			)
		)
		(property "Datasheet" "https://docs.xilinx.com/viewer/book-attachment/2PXOpPtpaABIt0fkzeBLnw/hvbsEUaOT0OxFhln7VEVyA"
			(at 214.63 73.66 0)
			(effects
				(font
					(size 1.27 1.27)
					(thickness 0.15)
				)
				(justify left bottom)
				(hide yes)
			)
		)
		(property "Description" ""
			(at 278.13 63.5 0)
			(effects
				(font
					(size 1.27 1.27)
				)
				(hide yes)
			)
		)
		(property "MPN" "XCAU25P-2FFVB676I"
			(at 262.89 55.245 0)
			(effects
				(font
					(size 1.27 1.27)
					(thickness 0.15)
				)
			)
		)
		(property "Manufacturer" "AMD-Xilinx"
			(at 214.63 76.2 0)
			(effects
				(font
					(size 1.27 1.27)
					(thickness 0.15)
				)
				(justify left bottom)
				(hide yes)
			)
		)
		(property "Author" "Antmicro"
			(at 214.63 78.74 0)
			(effects
				(font
					(size 1.27 1.27)
					(thickness 0.15)
				)
				(justify left bottom)
				(hide yes)
			)
		)
		(property "License" "Apache-2.0"
			(at 214.63 81.28 0)
			(effects
				(font
					(size 1.27 1.27)
					(thickness 0.15)
				)
				(justify left bottom)
				(hide yes)
			)
		)
		(pin "AC23"
		)
		(pin "P20"
		)
		(pin "N19"
		)
		(pin "AA24"
		)
		(pin "J16"
		)
		(pin "J21"
		)
		(pin "AE10"
		)
		(pin "F6"
		)
		(pin "F7"
		)
		(pin "AF17"
		)
		(pin "AA15"
		)
		(pin "J25"
		)
		(pin "Y21"
		)
		(pin "AA7"
		)
		(pin "E26"
		)
		(pin "AD16"
		)
		(pin "V1"
		)
		(pin "AB14"
		)
		(pin "Y1"
		)
		(pin "E24"
		)
		(pin "AA14"
		)
		(pin "J20"
		)
		(pin "U25"
		)
		(pin "AE18"
		)
		(pin "U22"
		)
		(pin "P4"
		)
		(pin "P5"
		)
		(pin "R1"
		)
		(pin "R10"
		)
		(pin "P8"
		)
		(pin "P9"
		)
		(pin "R11"
		)
		(pin "R12"
		)
		(pin "AD3"
		)
		(pin "AD9"
		)
		(pin "AD4"
		)
		(pin "P18"
		)
		(pin "P3"
		)
		(pin "G14"
		)
		(pin "AE26"
		)
		(pin "B12"
		)
		(pin "AC2"
		)
		(pin "W7"
		)
		(pin "W8"
		)
		(pin "W11"
		)
		(pin "W17"
		)
		(pin "W2"
		)
		(pin "W22"
		)
		(pin "W3"
		)
		(pin "W6"
		)
		(pin "P6"
		)
		(pin "U26"
		)
		(pin "P19"
		)
		(pin "U1"
		)
		(pin "U10"
		)
		(pin "J15"
		)
		(pin "AB25"
		)
		(pin "L23"
		)
		(pin "P24"
		)
		(pin "G16"
		)
		(pin "C10"
		)
		(pin "F14"
		)
		(pin "U24"
		)
		(pin "Y24"
		)
		(pin "Y11"
		)
		(pin "J26"
		)
		(pin "AB4"
		)
		(pin "AD18"
		)
		(pin "J24"
		)
		(pin "AF2"
		)
		(pin "B26"
		)
		(pin "U6"
		)
		(pin "U7"
		)
		(pin "M11"
		)
		(pin "M12"
		)
		(pin "T20"
		)
		(pin "V23"
		)
		(pin "AD10"
		)
		(pin "D1"
		)
		(pin "AF1"
		)
		(pin "C8"
		)
		(pin "U13"
		)
		(pin "U14"
		)
		(pin "AD19"
		)
		(pin "Y4"
		)
		(pin "Y5"
		)
		(pin "E23"
		)
		(pin "C6"
		)
		(pin "AE14"
		)
		(pin "D22"
		)
		(pin "C20"
		)
		(pin "AB17"
		)
		(pin "AD24"
		)
		(pin "L1"
		)
		(pin "L10"
		)
		(pin "AE3"
		)
		(pin "G21"
		)
		(pin "AA17"
		)
		(pin "D6"
		)
		(pin "M25"
		)
		(pin "R17"
		)
		(pin "R18"
		)
		(pin "AE15"
		)
		(pin "H7"
		)
		(pin "H8"
		)
		(pin "R6"
		)
		(pin "R7"
		)
		(pin "AB20"
		)
		(pin "C5"
		)
		(pin "Y14"
		)
		(pin "AE13"
		)
		(pin "C13"
		)
		(pin "W4"
		)
		(pin "P22"
		)
		(pin "AF6"
		)
		(pin "B8"
		)
		(pin "AF18"
		)
		(pin "G22"
		)
		(pin "J2"
		)
		(pin "J3"
		)
		(pin "L3"
		)
		(pin "L6"
		)
		(pin "P12"
		)
		(pin "P15"
		)
		(pin "Y12"
		)
		(pin "K18"
		)
		(pin "V10"
		)
		(pin "V11"
		)
		(pin "D7"
		)
		(pin "D8"
		)
		(pin "P23"
		)
		(pin "AA3"
		)
		(pin "AB18"
		)
		(pin "H18"
		)
		(pin "B6"
		)
		(pin "R24"
		)
		(pin "R3"
		)
		(pin "P16"
		)
		(pin "P17"
		)
		(pin "AF23"
		)
		(pin "AC14"
		)
		(pin "M6"
		)
		(pin "B18"
		)
		(pin "M1"
		)
		(pin "B5"
		)
		(pin "D2"
		)
		(pin "G20"
		)
		(pin "M2"
		)
		(pin "B4"
		)
		(pin "AA16"
		)
		(pin "V9"
		)
		(pin "W1"
		)
		(pin "N5"
		)
		(pin "AA26"
		)
		(pin "B3"
		)
		(pin "D12"
		)
		(pin "N4"
		)
		(pin "AA2"
		)
		(pin "B23"
		)
		(pin "C12"
		)
		(pin "L5"
		)
		(pin "AA6"
		)
		(pin "B1"
		)
		(pin "H1"
		)
		(pin "A14"
		)
		(pin "A13"
		)
		(pin "AB2"
		)
		(pin "AE4"
		)
		(pin "Y16"
		)
		(pin "B24"
		)
		(pin "H16"
		)
		(pin "W24"
		)
		(pin "D18"
		)
		(pin "B20"
		)
		(pin "D21"
		)
		(pin "B19"
		)
		(pin "B25"
		)
		(pin "C24"
		)
		(pin "A15"
		)
		(pin "M26"
		)
		(pin "A23"
		)
		(pin "C17"
		)
		(pin "K21"
		)
		(pin "W23"
		)
		(pin "L24"
		)
		(pin "R20"
		)
		(pin "C21"
		)
		(pin "D24"
		)
		(pin "E15"
		)
		(pin "AD12"
		)
		(pin "D23"
		)
		(pin "D25"
		)
		(pin "C26"
		)
		(pin "B21"
		)
		(pin "Y26"
		)
		(pin "AE25"
		)
		(pin "C19"
		)
		(pin "C23"
		)
		(pin "P21"
		)
		(pin "A20"
		)
		(pin "L18"
		)
		(pin "A25"
		)
		(pin "K23"
		)
		(pin "V18"
		)
		(pin "C16"
		)
		(pin "V21"
		)
		(pin "E17"
		)
		(pin "A17"
		)
		(pin "P25"
		)
		(pin "AD25"
		)
		(pin "G18"
		)
		(pin "AB3"
		)
		(pin "J6"
		)
		(pin "J7"
		)
		(pin "K12"
		)
		(pin "K13"
		)
		(pin "AB16"
		)
		(pin "C1"
		)
		(pin "AF15"
		)
		(pin "J8"
		)
		(pin "K11"
		)
		(pin "AD1"
		)
		(pin "F25"
		)
		(pin "AE1"
		)
		(pin "V2"
		)
		(pin "U2"
		)
		(pin "U3"
		)
		(pin "F2"
		)
		(pin "V6"
		)
		(pin "P1"
		)
		(pin "L13"
		)
		(pin "L14"
		)
		(pin "AD5"
		)
		(pin "AE8"
		)
		(pin "AB10"
		)
		(pin "U15"
		)
		(pin "U16"
		)
		(pin "U17"
		)
		(pin "U18"
		)
		(pin "D26"
		)
		(pin "G5"
		)
		(pin "E25"
		)
		(pin "AD22"
		)
		(pin "A19"
		)
		(pin "P7"
		)
		(pin "Y2"
		)
		(pin "J22"
		)
		(pin "Y19"
		)
		(pin "Y3"
		)
		(pin "AB7"
		)
		(pin "AF22"
		)
		(pin "B2"
		)
		(pin "AA10"
		)
		(pin "V7"
		)
		(pin "V22"
		)
		(pin "J23"
		)
		(pin "AF12"
		)
		(pin "V16"
		)
		(pin "V17"
		)
		(pin "Y7"
		)
		(pin "D15"
		)
		(pin "H12"
		)
		(pin "AF7"
		)
		(pin "U23"
		)
		(pin "V19"
		)
		(pin "AF14"
		)
		(pin "AF13"
		)
		(pin "G8"
		)
		(pin "H20"
		)
		(pin "U11"
		)
		(pin "U12"
		)
		(pin "A5"
		)
		(pin "G6"
		)
		(pin "G7"
		)
		(pin "L15"
		)
		(pin "L16"
		)
		(pin "T8"
		)
		(pin "T9"
		)
		(pin "G19"
		)
		(pin "G17"
		)
		(pin "T4"
		)
		(pin "T5"
		)
		(pin "B13"
		)
		(pin "G23"
		)
		(pin "G3"
		)
		(pin "T26"
		)
		(pin "T3"
		)
		(pin "G13"
		)
		(pin "G2"
		)
		(pin "D17"
		)
		(pin "AD15"
		)
		(pin "Y8"
		)
		(pin "Y9"
		)
		(pin "AC24"
		)
		(pin "AD8"
		)
		(pin "F8"
		)
		(pin "G1"
		)
		(pin "AD6"
		)
		(pin "F18"
		)
		(pin "H17"
		)
		(pin "AA13"
		)
		(pin "K20"
		)
		(pin "AD7"
		)
		(pin "AA1"
		)
		(pin "AF19"
		)
		(pin "Y15"
		)
		(pin "AB13"
		)
		(pin "N13"
		)
		(pin "N14"
		)
		(pin "V14"
		)
		(pin "V15"
		)
		(pin "U8"
		)
		(pin "U9"
		)
		(pin "W13"
		)
		(pin "V5"
		)
		(pin "V8"
		)
		(pin "W5"
		)
		(pin "P26"
		)
		(pin "Y20"
		)
		(pin "L17"
		)
		(pin "L2"
		)
		(pin "H26"
		)
		(pin "Y6"
		)
		(pin "AC22"
		)
		(pin "D13"
		)
		(pin "V12"
		)
		(pin "V13"
		)
		(pin "AE9"
		)
		(pin "B7"
		)
		(pin "A11"
		)
		(pin "K9"
		)
		(pin "L11"
		)
		(pin "L12"
		)
		(pin "H5"
		)
		(pin "H6"
		)
		(pin "AE19"
		)
		(pin "C18"
		)
		(pin "H13"
		)
		(pin "AB23"
		)
		(pin "AC26"
		)
		(pin "R19"
		)
		(pin "R2"
		)
		(pin "H19"
		)
		(pin "AF20"
		)
		(pin "AF24"
		)
		(pin "B22"
		)
		(pin "B14"
		)
		(pin "D4"
		)
		(pin "AA18"
		)
		(pin "C22"
		)
		(pin "V24"
		)
		(pin "A12"
		)
		(pin "C7"
		)
		(pin "M7"
		)
		(pin "AB5"
		)
		(pin "W18"
		)
		(pin "T18"
		)
		(pin "T21"
		)
		(pin "F13"
		)
		(pin "D3"
		)
		(pin "F1"
		)
		(pin "L21"
		)
		(pin "L26"
		)
		(pin "AA11"
		)
		(pin "M20"
		)
		(pin "AC4"
		)
		(pin "AE5"
		)
		(pin "D19"
		)
		(pin "E10"
		)
		(pin "AA9"
		)
		(pin "Y22"
		)
		(pin "V3"
		)
		(pin "V4"
		)
		(pin "AD2"
		)
		(pin "AC10"
		)
		(pin "C25"
		)
		(pin "G4"
		)
		(pin "A6"
		)
		(pin "E6"
		)
		(pin "E7"
		)
		(pin "E1"
		)
		(pin "E19"
		)
		(pin "R4"
		)
		(pin "T10"
		)
		(pin "T11"
		)
		(pin "J10"
		)
		(pin "F17"
		)
		(pin "A24"
		)
		(pin "AC15"
		)
		(pin "C15"
		)
		(pin "A1"
		)
		(pin "J1"
		)
		(pin "J17"
		)
		(pin "AE6"
		)
		(pin "E4"
		)
		(pin "E5"
		)
		(pin "M23"
		)
		(pin "M3"
		)
		(pin "R22"
		)
		(pin "AA5"
		)
		(pin "AC12"
		)
		(pin "Y18"
		)
		(pin "W20"
		)
		(pin "AC21"
		)
		(pin "R23"
		)
		(pin "K10"
		)
		(pin "AC17"
		)
		(pin "AC20"
		)
		(pin "V20"
		)
		(pin "V25"
		)
		(pin "N1"
		)
		(pin "N10"
		)
		(pin "M4"
		)
		(pin "M5"
		)
		(pin "R25"
		)
		(pin "H3"
		)
		(pin "H4"
		)
		(pin "AD13"
		)
		(pin "AD17"
		)
		(pin "N26"
		)
		(pin "R13"
		)
		(pin "N6"
		)
		(pin "N7"
		)
		(pin "U4"
		)
		(pin "R5"
		)
		(pin "K3"
		)
		(pin "K4"
		)
		(pin "AF3"
		)
		(pin "J5"
		)
		(pin "P2"
		)
		(pin "N22"
		)
		(pin "T16"
		)
		(pin "T17"
		)
		(pin "C3"
		)
		(pin "AF4"
		)
		(pin "T13"
		)
		(pin "AA12"
		)
		(pin "AB26"
		)
		(pin "AF21"
		)
		(pin "N25"
		)
		(pin "N3"
		)
		(pin "N21"
		)
		(pin "J12"
		)
		(pin "A8"
		)
		(pin "W12"
		)
		(pin "H14"
		)
		(pin "U21"
		)
		(pin "W9"
		)
		(pin "T14"
		)
		(pin "AE23"
		)
		(pin "K19"
		)
		(pin "K24"
		)
		(pin "Y25"
		)
		(pin "G12"
		)
		(pin "N2"
		)
		(pin "N20"
		)
		(pin "T25"
		)
		(pin "AC8"
		)
		(pin "E16"
		)
		(pin "AC19"
		)
		(pin "C14"
		)
		(pin "F4"
		)
		(pin "F5"
		)
		(pin "U19"
		)
		(pin "AE12"
		)
		(pin "P14"
		)
		(pin "AF8"
		)
		(pin "AF9"
		)
		(pin "V26"
		)
		(pin "W19"
		)
		(pin "L4"
		)
		(pin "G24"
		)
		(pin "R15"
		)
		(pin "R16"
		)
		(pin "U5"
		)
		(pin "AC16"
		)
		(pin "AF25"
		)
		(pin "T7"
		)
		(pin "F24"
		)
		(pin "D16"
		)
		(pin "AA19"
		)
		(pin "D5"
		)
		(pin "L22"
		)
		(pin "B17"
		)
		(pin "H15"
		)
		(pin "AE21"
		)
		(pin "AE7"
		)
		(pin "K5"
		)
		(pin "K6"
		)
		(pin "T1"
		)
		(pin "AE22"
		)
		(pin "E22"
		)
		(pin "AF10"
		)
		(pin "AB6"
		)
		(pin "AD26"
		)
		(pin "AC13"
		)
		(pin "E18"
		)
		(pin "M15"
		)
		(pin "M16"
		)
		(pin "G15"
		)
		(pin "N8"
		)
		(pin "N9"
		)
		(pin "W26"
		)
		(pin "F20"
		)
		(pin "AD23"
		)
		(pin "AA8"
		)
		(pin "D20"
		)
		(pin "AF11"
		)
		(pin "E8"
		)
		(pin "F11"
		)
		(pin "AC5"
		)
		(pin "AA22"
		)
		(pin "E20"
		)
		(pin "W14"
		)
		(pin "M19"
		)
		(pin "H24"
		)
		(pin "K7"
		)
		(pin "K8"
		)
		(pin "C4"
		)
		(pin "H25"
		)
		(pin "W21"
		)
		(pin "P13"
		)
		(pin "L20"
		)
		(pin "AB21"
		)
		(pin "C2"
		)
		(pin "H22"
		)
		(pin "Y17"
		)
		(pin "AE11"
		)
		(pin "H2"
		)
		(pin "F23"
		)
		(pin "E11"
		)
		(pin "AB24"
		)
		(pin "AA4"
		)
		(pin "T6"
		)
		(pin "AD20"
		)
		(pin "A10"
		)
		(pin "C9"
		)
		(pin "W15"
		)
		(pin "E21"
		)
		(pin "AB22"
		)
		(pin "W16"
		)
		(pin "AC25"
		)
		(pin "T22"
		)
		(pin "K1"
		)
		(pin "AD14"
		)
		(pin "T2"
		)
		(pin "J19"
		)
		(pin "D9"
		)
		(pin "AE17"
		)
		(pin "AB1"
		)
		(pin "T24"
		)
		(pin "F9"
		)
		(pin "M8"
		)
		(pin "M9"
		)
		(pin "Y23"
		)
		(pin "AC7"
		)
		(pin "M13"
		)
		(pin "M14"
		)
		(pin "G25"
		)
		(pin "A9"
		)
		(pin "AB19"
		)
		(pin "A7"
		)
		(pin "N15"
		)
		(pin "N16"
		)
		(pin "Y13"
		)
		(pin "AF5"
		)
		(pin "R14"
		)
		(pin "AE20"
		)
		(pin "AB11"
		)
		(pin "W25"
		)
		(pin "T19"
		)
		(pin "H21"
		)
		(pin "K2"
		)
		(pin "T23"
		)
		(pin "AC6"
		)
		(pin "B15"
		)
		(pin "E9"
		)
		(pin "AC3"
		)
		(pin "F10"
		)
		(pin "A3"
		)
		(pin "F15"
		)
		(pin "U20"
		)
		(pin "G10"
		)
		(pin "N23"
		)
		(pin "AB15"
		)
		(pin "AA21"
		)
		(pin "P10"
		)
		(pin "P11"
		)
		(pin "J11"
		)
		(pin "Y10"
		)
		(pin "F19"
		)
		(pin "A22"
		)
		(pin "AE16"
		)
		(pin "F22"
		)
		(pin "G11"
		)
		(pin "K25"
		)
		(pin "B10"
		)
		(pin "AA20"
		)
		(pin "N24"
		)
		(pin "AA25"
		)
		(pin "E12"
		)
		(pin "D11"
		)
		(pin "E14"
		)
		(pin "AC1"
		)
		(pin "J4"
		)
		(pin "H11"
		)
		(pin "H9"
		)
		(pin "M22"
		)
		(pin "H10"
		)
		(pin "E13"
		)
		(pin "AD21"
		)
		(pin "D10"
		)
		(pin "B11"
		)
		(pin "G26"
		)
		(pin "L25"
		)
		(pin "AB9"
		)
		(pin "A2"
		)
		(pin "M21"
		)
		(pin "C11"
		)
		(pin "R21"
		)
		(pin "D14"
		)
		(pin "F12"
		)
		(pin "B9"
		)
		(pin "J9"
		)
		(pin "L19"
		)
		(pin "B16"
		)
		(pin "K22"
		)
		(pin "K26"
		)
		(pin "N11"
		)
		(pin "N12"
		)
		(pin "A16"
		)
		(pin "AB12"
		)
		(pin "L7"
		)
		(pin "L8"
		)
		(pin "AC11"
		)
		(pin "J18"
		)
		(pin "K16"
		)
		(pin "K17"
		)
		(pin "M24"
		)
		(pin "M17"
		)
		(pin "M18"
		)
		(pin "J14"
		)
		(pin "R8"
		)
		(pin "R9"
		)
		(pin "A26"
		)
		(pin "H23"
		)
		(pin "AF16"
		)
		(pin "F26"
		)
		(pin "F3"
		)
		(pin "AC18"
		)
		(pin "W10"
		)
		(pin "G9"
		)
		(pin "K14"
		)
		(pin "K15"
		)
		(pin "N17"
		)
		(pin "N18"
		)
		(pin "AC9"
		)
		(pin "J13"
		)
		(pin "AE24"
		)
		(pin "AA23"
		)
		(pin "E2"
		)
		(pin "E3"
		)
		(pin "AE2"
		)
		(pin "AF26"
		)
		(pin "A21"
		)
		(pin "L9"
		)
		(pin "M10"
		)
		(pin "F16"
		)
		(pin "F21"
		)
		(pin "R26"
		)
		(pin "T12"
		)
		(pin "T15"
		)
		(pin "AB8"
		)
		(pin "A18"
		)
		(pin "A4"
		)
		(pin "AD11"
		)
		(instances
			(project "data-center-rdimm-ddr5-tester"
				(path ""
					(reference "U34")
					(unit 11)
				)
			)
		)
	)
	(symbol
		(lib_id "antmicroFPGAChips:XCAU25P-2FFVB676I")
		(at 76.2 77.47 0)
		(mirror y)
		(unit 9)
		(exclude_from_sim no)
		(in_bom yes)
		(on_board yes)
		(dnp no)
		(property "Reference" "U34"
			(at 68.58 66.04 0)
			(effects
				(font
					(size 1.27 1.27)
					(thickness 0.15)
				)
			)
		)
		(property "Value" "XCAU25P-2FFVB676I"
			(at 12.7 82.55 0)
			(effects
				(font
					(size 1.27 1.27)
					(thickness 0.15)
				)
				(justify left bottom)
				(hide yes)
			)
		)
		(property "Footprint" "antmicro-footprints:BGA-676_27x27mm_Layout26x26_P1x1mm_FFVB676"
			(at 12.7 85.09 0)
			(effects
				(font
					(size 1.27 1.27)
					(thickness 0.15)
				)
				(justify left bottom)
				(hide yes)
			)
		)
		(property "Datasheet" "https://docs.xilinx.com/viewer/book-attachment/2PXOpPtpaABIt0fkzeBLnw/hvbsEUaOT0OxFhln7VEVyA"
			(at 12.7 87.63 0)
			(effects
				(font
					(size 1.27 1.27)
					(thickness 0.15)
				)
				(justify left bottom)
				(hide yes)
			)
		)
		(property "Description" ""
			(at 76.2 77.47 0)
			(effects
				(font
					(size 1.27 1.27)
				)
				(hide yes)
			)
		)
		(property "MPN" "XCAU25P-2FFVB676I"
			(at 60.96 68.58 0)
			(effects
				(font
					(size 1.27 1.27)
					(thickness 0.15)
				)
			)
		)
		(property "Manufacturer" "AMD-Xilinx"
			(at 12.7 90.17 0)
			(effects
				(font
					(size 1.27 1.27)
					(thickness 0.15)
				)
				(justify left bottom)
				(hide yes)
			)
		)
		(property "Author" "Antmicro"
			(at 12.7 92.71 0)
			(effects
				(font
					(size 1.27 1.27)
					(thickness 0.15)
				)
				(justify left bottom)
				(hide yes)
			)
		)
		(property "License" "Apache-2.0"
			(at 12.7 95.25 0)
			(effects
				(font
					(size 1.27 1.27)
					(thickness 0.15)
				)
				(justify left bottom)
				(hide yes)
			)
		)
		(pin "AC23"
		)
		(pin "P20"
		)
		(pin "N19"
		)
		(pin "AA24"
		)
		(pin "J16"
		)
		(pin "J21"
		)
		(pin "AE10"
		)
		(pin "F6"
		)
		(pin "F7"
		)
		(pin "AF17"
		)
		(pin "AA15"
		)
		(pin "J25"
		)
		(pin "Y21"
		)
		(pin "AA7"
		)
		(pin "E26"
		)
		(pin "AD16"
		)
		(pin "V1"
		)
		(pin "AB14"
		)
		(pin "Y1"
		)
		(pin "E24"
		)
		(pin "AA14"
		)
		(pin "J20"
		)
		(pin "U25"
		)
		(pin "AE18"
		)
		(pin "U22"
		)
		(pin "P4"
		)
		(pin "P5"
		)
		(pin "R1"
		)
		(pin "R10"
		)
		(pin "P8"
		)
		(pin "P9"
		)
		(pin "R11"
		)
		(pin "R12"
		)
		(pin "AD3"
		)
		(pin "AD9"
		)
		(pin "AD4"
		)
		(pin "P18"
		)
		(pin "P3"
		)
		(pin "G14"
		)
		(pin "AE26"
		)
		(pin "B12"
		)
		(pin "AC2"
		)
		(pin "W7"
		)
		(pin "W8"
		)
		(pin "W11"
		)
		(pin "W17"
		)
		(pin "W2"
		)
		(pin "W22"
		)
		(pin "W3"
		)
		(pin "W6"
		)
		(pin "P6"
		)
		(pin "U26"
		)
		(pin "P19"
		)
		(pin "U1"
		)
		(pin "U10"
		)
		(pin "J15"
		)
		(pin "AB25"
		)
		(pin "L23"
		)
		(pin "P24"
		)
		(pin "G16"
		)
		(pin "C10"
		)
		(pin "F14"
		)
		(pin "U24"
		)
		(pin "Y24"
		)
		(pin "Y11"
		)
		(pin "J26"
		)
		(pin "AB4"
		)
		(pin "AD18"
		)
		(pin "J24"
		)
		(pin "AF2"
		)
		(pin "B26"
		)
		(pin "U6"
		)
		(pin "U7"
		)
		(pin "M11"
		)
		(pin "M12"
		)
		(pin "T20"
		)
		(pin "V23"
		)
		(pin "AD10"
		)
		(pin "D1"
		)
		(pin "AF1"
		)
		(pin "C8"
		)
		(pin "U13"
		)
		(pin "U14"
		)
		(pin "AD19"
		)
		(pin "Y4"
		)
		(pin "Y5"
		)
		(pin "E23"
		)
		(pin "C6"
		)
		(pin "AE14"
		)
		(pin "D22"
		)
		(pin "C20"
		)
		(pin "AB17"
		)
		(pin "AD24"
		)
		(pin "L1"
		)
		(pin "L10"
		)
		(pin "AE3"
		)
		(pin "G21"
		)
		(pin "AA17"
		)
		(pin "D6"
		)
		(pin "M25"
		)
		(pin "R17"
		)
		(pin "R18"
		)
		(pin "AE15"
		)
		(pin "H7"
		)
		(pin "H8"
		)
		(pin "R6"
		)
		(pin "R7"
		)
		(pin "AB20"
		)
		(pin "C5"
		)
		(pin "Y14"
		)
		(pin "AE13"
		)
		(pin "C13"
		)
		(pin "W4"
		)
		(pin "P22"
		)
		(pin "AF6"
		)
		(pin "B8"
		)
		(pin "AF18"
		)
		(pin "G22"
		)
		(pin "J2"
		)
		(pin "J3"
		)
		(pin "L3"
		)
		(pin "L6"
		)
		(pin "P12"
		)
		(pin "P15"
		)
		(pin "Y12"
		)
		(pin "K18"
		)
		(pin "V10"
		)
		(pin "V11"
		)
		(pin "D7"
		)
		(pin "D8"
		)
		(pin "P23"
		)
		(pin "AA3"
		)
		(pin "AB18"
		)
		(pin "H18"
		)
		(pin "B6"
		)
		(pin "R24"
		)
		(pin "R3"
		)
		(pin "P16"
		)
		(pin "P17"
		)
		(pin "AF23"
		)
		(pin "AC14"
		)
		(pin "M6"
		)
		(pin "B18"
		)
		(pin "M1"
		)
		(pin "B5"
		)
		(pin "D2"
		)
		(pin "G20"
		)
		(pin "M2"
		)
		(pin "B4"
		)
		(pin "AA16"
		)
		(pin "V9"
		)
		(pin "W1"
		)
		(pin "N5"
		)
		(pin "AA26"
		)
		(pin "B3"
		)
		(pin "D12"
		)
		(pin "N4"
		)
		(pin "AA2"
		)
		(pin "B23"
		)
		(pin "C12"
		)
		(pin "L5"
		)
		(pin "AA6"
		)
		(pin "B1"
		)
		(pin "H1"
		)
		(pin "A14"
		)
		(pin "A13"
		)
		(pin "AB2"
		)
		(pin "AE4"
		)
		(pin "Y16"
		)
		(pin "B24"
		)
		(pin "H16"
		)
		(pin "W24"
		)
		(pin "D18"
		)
		(pin "B20"
		)
		(pin "D21"
		)
		(pin "B19"
		)
		(pin "B25"
		)
		(pin "C24"
		)
		(pin "A15"
		)
		(pin "M26"
		)
		(pin "A23"
		)
		(pin "C17"
		)
		(pin "K21"
		)
		(pin "W23"
		)
		(pin "L24"
		)
		(pin "R20"
		)
		(pin "C21"
		)
		(pin "D24"
		)
		(pin "E15"
		)
		(pin "AD12"
		)
		(pin "D23"
		)
		(pin "D25"
		)
		(pin "C26"
		)
		(pin "B21"
		)
		(pin "Y26"
		)
		(pin "AE25"
		)
		(pin "C19"
		)
		(pin "C23"
		)
		(pin "P21"
		)
		(pin "A20"
		)
		(pin "L18"
		)
		(pin "A25"
		)
		(pin "K23"
		)
		(pin "V18"
		)
		(pin "C16"
		)
		(pin "V21"
		)
		(pin "E17"
		)
		(pin "A17"
		)
		(pin "P25"
		)
		(pin "AD25"
		)
		(pin "G18"
		)
		(pin "AB3"
		)
		(pin "J6"
		)
		(pin "J7"
		)
		(pin "K12"
		)
		(pin "K13"
		)
		(pin "AB16"
		)
		(pin "C1"
		)
		(pin "AF15"
		)
		(pin "J8"
		)
		(pin "K11"
		)
		(pin "AD1"
		)
		(pin "F25"
		)
		(pin "AE1"
		)
		(pin "V2"
		)
		(pin "U2"
		)
		(pin "U3"
		)
		(pin "F2"
		)
		(pin "V6"
		)
		(pin "P1"
		)
		(pin "L13"
		)
		(pin "L14"
		)
		(pin "AD5"
		)
		(pin "AE8"
		)
		(pin "AB10"
		)
		(pin "U15"
		)
		(pin "U16"
		)
		(pin "U17"
		)
		(pin "U18"
		)
		(pin "D26"
		)
		(pin "G5"
		)
		(pin "E25"
		)
		(pin "AD22"
		)
		(pin "A19"
		)
		(pin "P7"
		)
		(pin "Y2"
		)
		(pin "J22"
		)
		(pin "Y19"
		)
		(pin "Y3"
		)
		(pin "AB7"
		)
		(pin "AF22"
		)
		(pin "B2"
		)
		(pin "AA10"
		)
		(pin "V7"
		)
		(pin "V22"
		)
		(pin "J23"
		)
		(pin "AF12"
		)
		(pin "V16"
		)
		(pin "V17"
		)
		(pin "Y7"
		)
		(pin "D15"
		)
		(pin "H12"
		)
		(pin "AF7"
		)
		(pin "U23"
		)
		(pin "V19"
		)
		(pin "AF14"
		)
		(pin "AF13"
		)
		(pin "G8"
		)
		(pin "H20"
		)
		(pin "U11"
		)
		(pin "U12"
		)
		(pin "A5"
		)
		(pin "G6"
		)
		(pin "G7"
		)
		(pin "L15"
		)
		(pin "L16"
		)
		(pin "T8"
		)
		(pin "T9"
		)
		(pin "G19"
		)
		(pin "G17"
		)
		(pin "T4"
		)
		(pin "T5"
		)
		(pin "B13"
		)
		(pin "G23"
		)
		(pin "G3"
		)
		(pin "T26"
		)
		(pin "T3"
		)
		(pin "G13"
		)
		(pin "G2"
		)
		(pin "D17"
		)
		(pin "AD15"
		)
		(pin "Y8"
		)
		(pin "Y9"
		)
		(pin "AC24"
		)
		(pin "AD8"
		)
		(pin "F8"
		)
		(pin "G1"
		)
		(pin "AD6"
		)
		(pin "F18"
		)
		(pin "H17"
		)
		(pin "AA13"
		)
		(pin "K20"
		)
		(pin "AD7"
		)
		(pin "AA1"
		)
		(pin "AF19"
		)
		(pin "Y15"
		)
		(pin "AB13"
		)
		(pin "N13"
		)
		(pin "N14"
		)
		(pin "V14"
		)
		(pin "V15"
		)
		(pin "U8"
		)
		(pin "U9"
		)
		(pin "W13"
		)
		(pin "V5"
		)
		(pin "V8"
		)
		(pin "W5"
		)
		(pin "P26"
		)
		(pin "Y20"
		)
		(pin "L17"
		)
		(pin "L2"
		)
		(pin "H26"
		)
		(pin "Y6"
		)
		(pin "AC22"
		)
		(pin "D13"
		)
		(pin "V12"
		)
		(pin "V13"
		)
		(pin "AE9"
		)
		(pin "B7"
		)
		(pin "A11"
		)
		(pin "K9"
		)
		(pin "L11"
		)
		(pin "L12"
		)
		(pin "H5"
		)
		(pin "H6"
		)
		(pin "AE19"
		)
		(pin "C18"
		)
		(pin "H13"
		)
		(pin "AB23"
		)
		(pin "AC26"
		)
		(pin "R19"
		)
		(pin "R2"
		)
		(pin "H19"
		)
		(pin "AF20"
		)
		(pin "AF24"
		)
		(pin "B22"
		)
		(pin "B14"
		)
		(pin "D4"
		)
		(pin "AA18"
		)
		(pin "C22"
		)
		(pin "V24"
		)
		(pin "A12"
		)
		(pin "C7"
		)
		(pin "M7"
		)
		(pin "AB5"
		)
		(pin "W18"
		)
		(pin "T18"
		)
		(pin "T21"
		)
		(pin "F13"
		)
		(pin "D3"
		)
		(pin "F1"
		)
		(pin "L21"
		)
		(pin "L26"
		)
		(pin "AA11"
		)
		(pin "M20"
		)
		(pin "AC4"
		)
		(pin "AE5"
		)
		(pin "D19"
		)
		(pin "E10"
		)
		(pin "AA9"
		)
		(pin "Y22"
		)
		(pin "V3"
		)
		(pin "V4"
		)
		(pin "AD2"
		)
		(pin "AC10"
		)
		(pin "C25"
		)
		(pin "G4"
		)
		(pin "A6"
		)
		(pin "E6"
		)
		(pin "E7"
		)
		(pin "E1"
		)
		(pin "E19"
		)
		(pin "R4"
		)
		(pin "T10"
		)
		(pin "T11"
		)
		(pin "J10"
		)
		(pin "F17"
		)
		(pin "A24"
		)
		(pin "AC15"
		)
		(pin "C15"
		)
		(pin "A1"
		)
		(pin "J1"
		)
		(pin "J17"
		)
		(pin "AE6"
		)
		(pin "E4"
		)
		(pin "E5"
		)
		(pin "M23"
		)
		(pin "M3"
		)
		(pin "R22"
		)
		(pin "AA5"
		)
		(pin "AC12"
		)
		(pin "Y18"
		)
		(pin "W20"
		)
		(pin "AC21"
		)
		(pin "R23"
		)
		(pin "K10"
		)
		(pin "AC17"
		)
		(pin "AC20"
		)
		(pin "V20"
		)
		(pin "V25"
		)
		(pin "N1"
		)
		(pin "N10"
		)
		(pin "M4"
		)
		(pin "M5"
		)
		(pin "R25"
		)
		(pin "H3"
		)
		(pin "H4"
		)
		(pin "AD13"
		)
		(pin "AD17"
		)
		(pin "N26"
		)
		(pin "R13"
		)
		(pin "N6"
		)
		(pin "N7"
		)
		(pin "U4"
		)
		(pin "R5"
		)
		(pin "K3"
		)
		(pin "K4"
		)
		(pin "AF3"
		)
		(pin "J5"
		)
		(pin "P2"
		)
		(pin "N22"
		)
		(pin "T16"
		)
		(pin "T17"
		)
		(pin "C3"
		)
		(pin "AF4"
		)
		(pin "T13"
		)
		(pin "AA12"
		)
		(pin "AB26"
		)
		(pin "AF21"
		)
		(pin "N25"
		)
		(pin "N3"
		)
		(pin "N21"
		)
		(pin "J12"
		)
		(pin "A8"
		)
		(pin "W12"
		)
		(pin "H14"
		)
		(pin "U21"
		)
		(pin "W9"
		)
		(pin "T14"
		)
		(pin "AE23"
		)
		(pin "K19"
		)
		(pin "K24"
		)
		(pin "Y25"
		)
		(pin "G12"
		)
		(pin "N2"
		)
		(pin "N20"
		)
		(pin "T25"
		)
		(pin "AC8"
		)
		(pin "E16"
		)
		(pin "AC19"
		)
		(pin "C14"
		)
		(pin "F4"
		)
		(pin "F5"
		)
		(pin "U19"
		)
		(pin "AE12"
		)
		(pin "P14"
		)
		(pin "AF8"
		)
		(pin "AF9"
		)
		(pin "V26"
		)
		(pin "W19"
		)
		(pin "L4"
		)
		(pin "G24"
		)
		(pin "R15"
		)
		(pin "R16"
		)
		(pin "U5"
		)
		(pin "AC16"
		)
		(pin "AF25"
		)
		(pin "T7"
		)
		(pin "F24"
		)
		(pin "D16"
		)
		(pin "AA19"
		)
		(pin "D5"
		)
		(pin "L22"
		)
		(pin "B17"
		)
		(pin "H15"
		)
		(pin "AE21"
		)
		(pin "AE7"
		)
		(pin "K5"
		)
		(pin "K6"
		)
		(pin "T1"
		)
		(pin "AE22"
		)
		(pin "E22"
		)
		(pin "AF10"
		)
		(pin "AB6"
		)
		(pin "AD26"
		)
		(pin "AC13"
		)
		(pin "E18"
		)
		(pin "M15"
		)
		(pin "M16"
		)
		(pin "G15"
		)
		(pin "N8"
		)
		(pin "N9"
		)
		(pin "W26"
		)
		(pin "F20"
		)
		(pin "AD23"
		)
		(pin "AA8"
		)
		(pin "D20"
		)
		(pin "AF11"
		)
		(pin "E8"
		)
		(pin "F11"
		)
		(pin "AC5"
		)
		(pin "AA22"
		)
		(pin "E20"
		)
		(pin "W14"
		)
		(pin "M19"
		)
		(pin "H24"
		)
		(pin "K7"
		)
		(pin "K8"
		)
		(pin "C4"
		)
		(pin "H25"
		)
		(pin "W21"
		)
		(pin "P13"
		)
		(pin "L20"
		)
		(pin "AB21"
		)
		(pin "C2"
		)
		(pin "H22"
		)
		(pin "Y17"
		)
		(pin "AE11"
		)
		(pin "H2"
		)
		(pin "F23"
		)
		(pin "E11"
		)
		(pin "AB24"
		)
		(pin "AA4"
		)
		(pin "T6"
		)
		(pin "AD20"
		)
		(pin "A10"
		)
		(pin "C9"
		)
		(pin "W15"
		)
		(pin "E21"
		)
		(pin "AB22"
		)
		(pin "W16"
		)
		(pin "AC25"
		)
		(pin "T22"
		)
		(pin "K1"
		)
		(pin "AD14"
		)
		(pin "T2"
		)
		(pin "J19"
		)
		(pin "D9"
		)
		(pin "AE17"
		)
		(pin "AB1"
		)
		(pin "T24"
		)
		(pin "F9"
		)
		(pin "M8"
		)
		(pin "M9"
		)
		(pin "Y23"
		)
		(pin "AC7"
		)
		(pin "M13"
		)
		(pin "M14"
		)
		(pin "G25"
		)
		(pin "A9"
		)
		(pin "AB19"
		)
		(pin "A7"
		)
		(pin "N15"
		)
		(pin "N16"
		)
		(pin "Y13"
		)
		(pin "AF5"
		)
		(pin "R14"
		)
		(pin "AE20"
		)
		(pin "AB11"
		)
		(pin "W25"
		)
		(pin "T19"
		)
		(pin "H21"
		)
		(pin "K2"
		)
		(pin "T23"
		)
		(pin "AC6"
		)
		(pin "B15"
		)
		(pin "E9"
		)
		(pin "AC3"
		)
		(pin "F10"
		)
		(pin "A3"
		)
		(pin "F15"
		)
		(pin "U20"
		)
		(pin "G10"
		)
		(pin "N23"
		)
		(pin "AB15"
		)
		(pin "AA21"
		)
		(pin "P10"
		)
		(pin "P11"
		)
		(pin "J11"
		)
		(pin "Y10"
		)
		(pin "F19"
		)
		(pin "A22"
		)
		(pin "AE16"
		)
		(pin "F22"
		)
		(pin "G11"
		)
		(pin "K25"
		)
		(pin "B10"
		)
		(pin "AA20"
		)
		(pin "N24"
		)
		(pin "AA25"
		)
		(pin "E12"
		)
		(pin "D11"
		)
		(pin "E14"
		)
		(pin "AC1"
		)
		(pin "J4"
		)
		(pin "H11"
		)
		(pin "H9"
		)
		(pin "M22"
		)
		(pin "H10"
		)
		(pin "E13"
		)
		(pin "AD21"
		)
		(pin "D10"
		)
		(pin "B11"
		)
		(pin "G26"
		)
		(pin "L25"
		)
		(pin "AB9"
		)
		(pin "A2"
		)
		(pin "M21"
		)
		(pin "C11"
		)
		(pin "R21"
		)
		(pin "D14"
		)
		(pin "F12"
		)
		(pin "B9"
		)
		(pin "J9"
		)
		(pin "L19"
		)
		(pin "B16"
		)
		(pin "K22"
		)
		(pin "K26"
		)
		(pin "N11"
		)
		(pin "N12"
		)
		(pin "A16"
		)
		(pin "AB12"
		)
		(pin "L7"
		)
		(pin "L8"
		)
		(pin "AC11"
		)
		(pin "J18"
		)
		(pin "K16"
		)
		(pin "K17"
		)
		(pin "M24"
		)
		(pin "M17"
		)
		(pin "M18"
		)
		(pin "J14"
		)
		(pin "R8"
		)
		(pin "R9"
		)
		(pin "A26"
		)
		(pin "H23"
		)
		(pin "AF16"
		)
		(pin "F26"
		)
		(pin "F3"
		)
		(pin "AC18"
		)
		(pin "W10"
		)
		(pin "G9"
		)
		(pin "K14"
		)
		(pin "K15"
		)
		(pin "N17"
		)
		(pin "N18"
		)
		(pin "AC9"
		)
		(pin "J13"
		)
		(pin "AE24"
		)
		(pin "AA23"
		)
		(pin "E2"
		)
		(pin "E3"
		)
		(pin "AE2"
		)
		(pin "AF26"
		)
		(pin "A21"
		)
		(pin "L9"
		)
		(pin "M10"
		)
		(pin "F16"
		)
		(pin "F21"
		)
		(pin "R26"
		)
		(pin "T12"
		)
		(pin "T15"
		)
		(pin "AB8"
		)
		(pin "A18"
		)
		(pin "A4"
		)
		(pin "AD11"
		)
		(instances
			(project "data-center-rdimm-ddr5-tester"
				(path ""
					(reference "U34")
					(unit 9)
				)
			)
		)
	)
	(symbol
		(lib_id "antmicropower:+3V3")
		(at 309.88 163.83 0)
		(mirror y)
		(unit 1)
		(exclude_from_sim no)
		(in_bom yes)
		(on_board yes)
		(dnp no)
		(fields_autoplaced yes)
		(property "Reference" "#PWR0535"
			(at 294.64 163.83 0)
			(effects
				(font
					(size 1.27 1.27)
					(thickness 0.15)
				)
				(justify left bottom)
				(hide yes)
			)
		)
		(property "Value" "+3V3"
			(at 309.88 158.75 0)
			(effects
				(font
					(size 1.27 1.27)
					(thickness 0.15)
				)
			)
		)
		(property "Footprint" ""
			(at 294.64 171.45 0)
			(effects
				(font
					(size 1.27 1.27)
					(thickness 0.15)
				)
				(justify left bottom)
				(hide yes)
			)
		)
		(property "Datasheet" ""
			(at 294.64 173.99 0)
			(effects
				(font
					(size 1.27 1.27)
					(thickness 0.15)
				)
				(justify left bottom)
				(hide yes)
			)
		)
		(property "Description" ""
			(at 309.88 163.83 0)
			(effects
				(font
					(size 1.27 1.27)
				)
				(hide yes)
			)
		)
		(property "Author" "Antmicro"
			(at 294.64 166.37 0)
			(effects
				(font
					(size 1.27 1.27)
					(thickness 0.15)
				)
				(justify left bottom)
				(hide yes)
			)
		)
		(property "License" "Apache-2.0"
			(at 294.64 168.91 0)
			(effects
				(font
					(size 1.27 1.27)
					(thickness 0.15)
				)
				(justify left bottom)
				(hide yes)
			)
		)
		(pin "1"
		)
		(instances
			(project "data-center-rdimm-ddr5-tester"
				(path ""
					(reference "#PWR0535")
					(unit 1)
				)
			)
		)
	)
	(symbol
		(lib_id "antmicroCapacitors0402:C_100n_0402")
		(at 325.12 62.23 0)
		(mirror y)
		(unit 1)
		(exclude_from_sim no)
		(in_bom yes)
		(on_board yes)
		(dnp no)
		(property "Reference" "C279"
			(at 318.77 60.96 0)
			(effects
				(font
					(size 1.27 1.27)
				)
			)
		)
		(property "Value" "C_100n_0402"
			(at 304.8 72.39 0)
			(effects
				(font
					(size 1.27 1.27)
					(thickness 0.15)
				)
				(justify left bottom)
				(hide yes)
			)
		)
		(property "Footprint" "antmicro-footprints:C_0402_1005Metric"
			(at 304.8 74.93 0)
			(effects
				(font
					(size 1.27 1.27)
					(thickness 0.15)
				)
				(justify left bottom)
				(hide yes)
			)
		)
		(property "Datasheet" "https://www.murata.com/products/productdetail?partno=GRM155R61H104KE14%23"
			(at 304.8 77.47 0)
			(effects
				(font
					(size 1.27 1.27)
					(thickness 0.15)
				)
				(justify left bottom)
				(hide yes)
			)
		)
		(property "Description" ""
			(at 325.12 62.23 0)
			(effects
				(font
					(size 1.27 1.27)
				)
				(hide yes)
			)
		)
		(property "Manufacturer" "Murata"
			(at 304.8 82.55 0)
			(effects
				(font
					(size 1.27 1.27)
					(thickness 0.15)
				)
				(justify left bottom)
				(hide yes)
			)
		)
		(property "MPN" "GRM155R61H104KE14D"
			(at 304.8 80.01 0)
			(effects
				(font
					(size 1.27 1.27)
					(thickness 0.15)
				)
				(justify left bottom)
				(hide yes)
			)
		)
		(property "Val" "100n"
			(at 318.77 63.5 0)
			(effects
				(font
					(size 1.27 1.27)
					(thickness 0.15)
				)
			)
		)
		(property "License" "Apache-2.0"
			(at 304.8 85.09 0)
			(effects
				(font
					(size 1.27 1.27)
					(thickness 0.15)
				)
				(justify left bottom)
				(hide yes)
			)
		)
		(property "Author" "Antmicro"
			(at 304.8 87.63 0)
			(effects
				(font
					(size 1.27 1.27)
					(thickness 0.15)
				)
				(justify left bottom)
				(hide yes)
			)
		)
		(property "Voltage" "50V"
			(at 304.8 90.17 0)
			(effects
				(font
					(size 1.27 1.27)
				)
				(justify left bottom)
				(hide yes)
			)
		)
		(property "Dielectric" "X5R"
			(at 304.8 92.71 0)
			(effects
				(font
					(size 1.27 1.27)
				)
				(justify left bottom)
				(hide yes)
			)
		)
		(pin "1"
		)
		(pin "2"
		)
		(instances
			(project "data-center-rdimm-ddr5-tester"
				(path ""
					(reference "C279")
					(unit 1)
				)
			)
		)
	)
	(symbol
		(lib_id "antmicroResistors0402:R_100R_0402")
		(at 270.51 203.2 90)
		(unit 1)
		(exclude_from_sim no)
		(in_bom yes)
		(on_board yes)
		(dnp no)
		(property "Reference" "R35"
			(at 269.24 199.39 90)
			(effects
				(font
					(size 1.27 1.27)
					(thickness 0.15)
				)
				(justify left)
			)
		)
		(property "Value" "R_100R_0402"
			(at 283.21 182.88 0)
			(effects
				(font
					(size 1.27 1.27)
					(thickness 0.15)
				)
				(justify left bottom)
				(hide yes)
			)
		)
		(property "Footprint" "antmicro-footprints:R_0402_1005Metric_EIA"
			(at 285.75 182.88 0)
			(effects
				(font
					(size 1.27 1.27)
					(thickness 0.15)
				)
				(justify left bottom)
				(hide yes)
			)
		)
		(property "Datasheet" "https://www.bourns.com/docs/product-datasheets/cr.pdf"
			(at 288.29 182.88 0)
			(effects
				(font
					(size 1.27 1.27)
					(thickness 0.15)
				)
				(justify left bottom)
				(hide yes)
			)
		)
		(property "Description" ""
			(at 270.51 203.2 0)
			(effects
				(font
					(size 1.27 1.27)
				)
				(hide yes)
			)
		)
		(property "MPN" "CR0402-FX-1000GLF"
			(at 290.83 182.88 0)
			(effects
				(font
					(size 1.27 1.27)
					(thickness 0.15)
				)
				(justify left bottom)
				(hide yes)
			)
		)
		(property "Manufacturer" "Bourns"
			(at 293.37 182.88 0)
			(effects
				(font
					(size 1.27 1.27)
					(thickness 0.15)
				)
				(justify left bottom)
				(hide yes)
			)
		)
		(property "License" "Apache-2.0"
			(at 295.91 182.88 0)
			(effects
				(font
					(size 1.27 1.27)
					(thickness 0.15)
				)
				(justify left bottom)
				(hide yes)
			)
		)
		(property "Author" "Antmicro"
			(at 298.45 182.88 0)
			(effects
				(font
					(size 1.27 1.27)
					(thickness 0.15)
				)
				(justify left bottom)
				(hide yes)
			)
		)
		(property "Val" "100R"
			(at 269.24 201.93 90)
			(effects
				(font
					(size 1.27 1.27)
					(thickness 0.15)
				)
				(justify left)
			)
		)
		(property "Tolerance" "1%"
			(at 280.67 182.88 0)
			(effects
				(font
					(size 1.27 1.27)
				)
				(justify left bottom)
				(hide yes)
			)
		)
		(pin "2"
		)
		(pin "1"
		)
		(instances
			(project "data-center-rdimm-ddr5-tester"
				(path ""
					(reference "R35")
					(unit 1)
				)
			)
		)
	)
	(symbol
		(lib_id "antmicroCapacitors0402:C_100n_0402")
		(at 328.93 106.68 180)
		(unit 1)
		(exclude_from_sim no)
		(in_bom yes)
		(on_board yes)
		(dnp no)
		(property "Reference" "C302"
			(at 330.2 105.41 0)
			(effects
				(font
					(size 1.27 1.27)
				)
			)
		)
		(property "Value" "C_100n_0402"
			(at 308.61 96.52 0)
			(effects
				(font
					(size 1.27 1.27)
					(thickness 0.15)
				)
				(justify left bottom)
				(hide yes)
			)
		)
		(property "Footprint" "antmicro-footprints:C_0402_1005Metric"
			(at 308.61 93.98 0)
			(effects
				(font
					(size 1.27 1.27)
					(thickness 0.15)
				)
				(justify left bottom)
				(hide yes)
			)
		)
		(property "Datasheet" "https://www.murata.com/products/productdetail?partno=GRM155R61H104KE14%23"
			(at 308.61 91.44 0)
			(effects
				(font
					(size 1.27 1.27)
					(thickness 0.15)
				)
				(justify left bottom)
				(hide yes)
			)
		)
		(property "Description" ""
			(at 328.93 106.68 0)
			(effects
				(font
					(size 1.27 1.27)
				)
				(hide yes)
			)
		)
		(property "Manufacturer" "Murata"
			(at 308.61 86.36 0)
			(effects
				(font
					(size 1.27 1.27)
					(thickness 0.15)
				)
				(justify left bottom)
				(hide yes)
			)
		)
		(property "MPN" "GRM155R61H104KE14D"
			(at 308.61 88.9 0)
			(effects
				(font
					(size 1.27 1.27)
					(thickness 0.15)
				)
				(justify left bottom)
				(hide yes)
			)
		)
		(property "Val" "100n"
			(at 330.2 107.95 0)
			(effects
				(font
					(size 1.27 1.27)
					(thickness 0.15)
				)
			)
		)
		(property "License" "Apache-2.0"
			(at 308.61 83.82 0)
			(effects
				(font
					(size 1.27 1.27)
					(thickness 0.15)
				)
				(justify left bottom)
				(hide yes)
			)
		)
		(property "Author" "Antmicro"
			(at 308.61 81.28 0)
			(effects
				(font
					(size 1.27 1.27)
					(thickness 0.15)
				)
				(justify left bottom)
				(hide yes)
			)
		)
		(property "Voltage" "50V"
			(at 308.61 78.74 0)
			(effects
				(font
					(size 1.27 1.27)
				)
				(justify left bottom)
				(hide yes)
			)
		)
		(property "Dielectric" "X5R"
			(at 308.61 76.2 0)
			(effects
				(font
					(size 1.27 1.27)
				)
				(justify left bottom)
				(hide yes)
			)
		)
		(pin "1"
		)
		(pin "2"
		)
		(instances
			(project "data-center-rdimm-ddr5-tester"
				(path ""
					(reference "C302")
					(unit 1)
				)
			)
		)
	)
	(symbol
		(lib_id "antmicroTestPoints:TP_0.75mm_SMD")
		(at 303.53 207.01 180)
		(unit 1)
		(exclude_from_sim no)
		(in_bom no)
		(on_board yes)
		(dnp no)
		(property "Reference" "TP5"
			(at 297.18 207.01 0)
			(effects
				(font
					(size 1.27 1.27)
					(thickness 0.15)
				)
			)
		)
		(property "Value" "TP_0.75mm_SMD"
			(at 293.37 203.2 0)
			(effects
				(font
					(size 1.27 1.27)
					(thickness 0.15)
				)
				(justify left bottom)
				(hide yes)
			)
		)
		(property "Footprint" "antmicro-footprints:TP_SMD_0.75mm"
			(at 293.37 200.66 0)
			(effects
				(font
					(size 1.27 1.27)
					(thickness 0.15)
				)
				(justify left bottom)
				(hide yes)
			)
		)
		(property "Datasheet" ""
			(at 285.75 194.31 0)
			(effects
				(font
					(size 1.27 1.27)
					(thickness 0.15)
				)
				(justify left bottom)
				(hide yes)
			)
		)
		(property "Description" ""
			(at 303.53 207.01 0)
			(effects
				(font
					(size 1.27 1.27)
				)
				(hide yes)
			)
		)
		(property "MPN" ""
			(at 292.735 195.58 0)
			(effects
				(font
					(size 1.27 1.27)
					(thickness 0.15)
				)
				(justify left bottom)
				(hide yes)
			)
		)
		(property "Manufacturer" ""
			(at 292.735 200.66 0)
			(effects
				(font
					(size 1.27 1.27)
					(thickness 0.15)
				)
				(justify left bottom)
				(hide yes)
			)
		)
		(property "Author" "Antmicro"
			(at 293.37 198.12 0)
			(effects
				(font
					(size 1.27 1.27)
					(thickness 0.15)
				)
				(justify left bottom)
				(hide yes)
			)
		)
		(property "License" "Apache-2.0"
			(at 293.37 195.58 0)
			(effects
				(font
					(size 1.27 1.27)
					(thickness 0.15)
				)
				(justify left bottom)
				(hide yes)
			)
		)
		(pin "1"
		)
		(instances
			(project "data-center-rdimm-ddr5-tester"
				(path ""
					(reference "TP5")
					(unit 1)
				)
			)
		)
	)
	(symbol
		(lib_id "antmicroCapacitors0402:C_100n_0402")
		(at 238.76 173.99 90)
		(mirror x)
		(unit 1)
		(exclude_from_sim no)
		(in_bom yes)
		(on_board yes)
		(dnp no)
		(property "Reference" "C285"
			(at 240.03 180.34 0)
			(effects
				(font
					(size 1.27 1.27)
					(thickness 0.15)
				)
			)
		)
		(property "Value" "C_100n_0402"
			(at 248.92 194.31 0)
			(effects
				(font
					(size 1.27 1.27)
					(thickness 0.15)
				)
				(justify left bottom)
				(hide yes)
			)
		)
		(property "Footprint" "antmicro-footprints:C_0402_1005Metric"
			(at 251.46 194.31 0)
			(effects
				(font
					(size 1.27 1.27)
					(thickness 0.15)
				)
				(justify left bottom)
				(hide yes)
			)
		)
		(property "Datasheet" "https://www.murata.com/products/productdetail?partno=GRM155R61H104KE14%23"
			(at 254 194.31 0)
			(effects
				(font
					(size 1.27 1.27)
					(thickness 0.15)
				)
				(justify left bottom)
				(hide yes)
			)
		)
		(property "Description" ""
			(at 238.76 173.99 0)
			(effects
				(font
					(size 1.27 1.27)
				)
				(hide yes)
			)
		)
		(property "MPN" "GRM155R61H104KE14D"
			(at 256.54 194.31 0)
			(effects
				(font
					(size 1.27 1.27)
					(thickness 0.15)
				)
				(justify left bottom)
				(hide yes)
			)
		)
		(property "Manufacturer" "Murata"
			(at 259.08 194.31 0)
			(effects
				(font
					(size 1.27 1.27)
					(thickness 0.15)
				)
				(justify left bottom)
				(hide yes)
			)
		)
		(property "License" "Apache-2.0"
			(at 261.62 194.31 0)
			(effects
				(font
					(size 1.27 1.27)
					(thickness 0.15)
				)
				(justify left bottom)
				(hide yes)
			)
		)
		(property "Author" "Antmicro"
			(at 264.16 194.31 0)
			(effects
				(font
					(size 1.27 1.27)
					(thickness 0.15)
				)
				(justify left bottom)
				(hide yes)
			)
		)
		(property "Val" "100n"
			(at 241.3 170.18 0)
			(effects
				(font
					(size 1.27 1.27)
					(thickness 0.15)
				)
				(justify left bottom)
			)
		)
		(property "Voltage" "50V"
			(at 266.7 194.31 0)
			(effects
				(font
					(size 1.27 1.27)
				)
				(justify left bottom)
				(hide yes)
			)
		)
		(property "Dielectric" "X5R"
			(at 269.24 194.31 0)
			(effects
				(font
					(size 1.27 1.27)
				)
				(justify left bottom)
				(hide yes)
			)
		)
		(property "Public" ""
			(at 271.78 194.31 0)
			(effects
				(font
					(size 1.27 1.27)
				)
				(justify left bottom)
				(hide yes)
			)
		)
		(pin "2"
		)
		(pin "1"
		)
		(instances
			(project "data-center-rdimm-ddr5-tester"
				(path ""
					(reference "C285")
					(unit 1)
				)
			)
		)
	)
	(symbol
		(lib_id "antmicroCapacitors0402:C_100n_0402")
		(at 142.24 107.95 0)
		(mirror y)
		(unit 1)
		(exclude_from_sim no)
		(in_bom yes)
		(on_board yes)
		(dnp no)
		(property "Reference" "C257"
			(at 143.51 106.68 0)
			(effects
				(font
					(size 1.27 1.27)
				)
			)
		)
		(property "Value" "C_100n_0402"
			(at 121.92 118.11 0)
			(effects
				(font
					(size 1.27 1.27)
					(thickness 0.15)
				)
				(justify left bottom)
				(hide yes)
			)
		)
		(property "Footprint" "antmicro-footprints:C_0402_1005Metric"
			(at 121.92 120.65 0)
			(effects
				(font
					(size 1.27 1.27)
					(thickness 0.15)
				)
				(justify left bottom)
				(hide yes)
			)
		)
		(property "Datasheet" "https://www.murata.com/products/productdetail?partno=GRM155R61H104KE14%23"
			(at 121.92 123.19 0)
			(effects
				(font
					(size 1.27 1.27)
					(thickness 0.15)
				)
				(justify left bottom)
				(hide yes)
			)
		)
		(property "Description" ""
			(at 142.24 107.95 0)
			(effects
				(font
					(size 1.27 1.27)
				)
				(hide yes)
			)
		)
		(property "Manufacturer" "Murata"
			(at 121.92 128.27 0)
			(effects
				(font
					(size 1.27 1.27)
					(thickness 0.15)
				)
				(justify left bottom)
				(hide yes)
			)
		)
		(property "MPN" "GRM155R61H104KE14D"
			(at 121.92 125.73 0)
			(effects
				(font
					(size 1.27 1.27)
					(thickness 0.15)
				)
				(justify left bottom)
				(hide yes)
			)
		)
		(property "Val" "100n"
			(at 136.525 106.68 0)
			(effects
				(font
					(size 1.27 1.27)
					(thickness 0.15)
				)
			)
		)
		(property "License" "Apache-2.0"
			(at 121.92 130.81 0)
			(effects
				(font
					(size 1.27 1.27)
					(thickness 0.15)
				)
				(justify left bottom)
				(hide yes)
			)
		)
		(property "Author" "Antmicro"
			(at 121.92 133.35 0)
			(effects
				(font
					(size 1.27 1.27)
					(thickness 0.15)
				)
				(justify left bottom)
				(hide yes)
			)
		)
		(property "Voltage" "50V"
			(at 121.92 135.89 0)
			(effects
				(font
					(size 1.27 1.27)
				)
				(justify left bottom)
				(hide yes)
			)
		)
		(property "Dielectric" "X5R"
			(at 121.92 138.43 0)
			(effects
				(font
					(size 1.27 1.27)
				)
				(justify left bottom)
				(hide yes)
			)
		)
		(pin "1"
		)
		(pin "2"
		)
		(instances
			(project "data-center-rdimm-ddr5-tester"
				(path ""
					(reference "C257")
					(unit 1)
				)
			)
		)
	)
	(symbol
		(lib_id "antmicropower:GND")
		(at 233.68 184.15 0)
		(mirror y)
		(unit 1)
		(exclude_from_sim no)
		(in_bom yes)
		(on_board yes)
		(dnp no)
		(property "Reference" "#PWR075"
			(at 224.79 186.69 0)
			(effects
				(font
					(size 1.27 1.27)
					(thickness 0.15)
				)
				(justify left bottom)
				(hide yes)
			)
		)
		(property "Value" "GND"
			(at 233.68 187.96 0)
			(effects
				(font
					(size 1.27 1.27)
					(thickness 0.15)
				)
			)
		)
		(property "Footprint" ""
			(at 224.79 191.77 0)
			(effects
				(font
					(size 1.27 1.27)
					(thickness 0.15)
				)
				(justify left bottom)
				(hide yes)
			)
		)
		(property "Datasheet" ""
			(at 224.79 196.85 0)
			(effects
				(font
					(size 1.27 1.27)
					(thickness 0.15)
				)
				(justify left bottom)
				(hide yes)
			)
		)
		(property "Description" ""
			(at 233.68 184.15 0)
			(effects
				(font
					(size 1.27 1.27)
				)
				(hide yes)
			)
		)
		(property "Author" "Antmicro"
			(at 224.79 191.77 0)
			(effects
				(font
					(size 1.27 1.27)
					(thickness 0.15)
				)
				(justify left bottom)
				(hide yes)
			)
		)
		(property "License" "Apache-2.0"
			(at 224.79 194.31 0)
			(effects
				(font
					(size 1.27 1.27)
					(thickness 0.15)
				)
				(justify left bottom)
				(hide yes)
			)
		)
		(pin "1"
		)
		(instances
			(project "data-center-rdimm-ddr5-tester"
				(path ""
					(reference "#PWR075")
					(unit 1)
				)
			)
		)
	)
	(symbol
		(lib_id "antmicroCapacitors0402:C_100n_0402")
		(at 228.6 173.99 90)
		(mirror x)
		(unit 1)
		(exclude_from_sim no)
		(in_bom yes)
		(on_board yes)
		(dnp no)
		(property "Reference" "C287"
			(at 229.87 180.34 0)
			(effects
				(font
					(size 1.27 1.27)
					(thickness 0.15)
				)
			)
		)
		(property "Value" "C_100n_0402"
			(at 238.76 194.31 0)
			(effects
				(font
					(size 1.27 1.27)
					(thickness 0.15)
				)
				(justify left bottom)
				(hide yes)
			)
		)
		(property "Footprint" "antmicro-footprints:C_0402_1005Metric"
			(at 241.3 194.31 0)
			(effects
				(font
					(size 1.27 1.27)
					(thickness 0.15)
				)
				(justify left bottom)
				(hide yes)
			)
		)
		(property "Datasheet" "https://www.murata.com/products/productdetail?partno=GRM155R61H104KE14%23"
			(at 243.84 194.31 0)
			(effects
				(font
					(size 1.27 1.27)
					(thickness 0.15)
				)
				(justify left bottom)
				(hide yes)
			)
		)
		(property "Description" ""
			(at 228.6 173.99 0)
			(effects
				(font
					(size 1.27 1.27)
				)
				(hide yes)
			)
		)
		(property "MPN" "GRM155R61H104KE14D"
			(at 246.38 194.31 0)
			(effects
				(font
					(size 1.27 1.27)
					(thickness 0.15)
				)
				(justify left bottom)
				(hide yes)
			)
		)
		(property "Manufacturer" "Murata"
			(at 248.92 194.31 0)
			(effects
				(font
					(size 1.27 1.27)
					(thickness 0.15)
				)
				(justify left bottom)
				(hide yes)
			)
		)
		(property "License" "Apache-2.0"
			(at 251.46 194.31 0)
			(effects
				(font
					(size 1.27 1.27)
					(thickness 0.15)
				)
				(justify left bottom)
				(hide yes)
			)
		)
		(property "Author" "Antmicro"
			(at 254 194.31 0)
			(effects
				(font
					(size 1.27 1.27)
					(thickness 0.15)
				)
				(justify left bottom)
				(hide yes)
			)
		)
		(property "Val" "100n"
			(at 231.14 170.18 0)
			(effects
				(font
					(size 1.27 1.27)
					(thickness 0.15)
				)
				(justify left bottom)
			)
		)
		(property "Voltage" "50V"
			(at 256.54 194.31 0)
			(effects
				(font
					(size 1.27 1.27)
				)
				(justify left bottom)
				(hide yes)
			)
		)
		(property "Dielectric" "X5R"
			(at 259.08 194.31 0)
			(effects
				(font
					(size 1.27 1.27)
				)
				(justify left bottom)
				(hide yes)
			)
		)
		(property "Public" ""
			(at 261.62 194.31 0)
			(effects
				(font
					(size 1.27 1.27)
				)
				(justify left bottom)
				(hide yes)
			)
		)
		(pin "2"
		)
		(pin "1"
		)
		(instances
			(project "data-center-rdimm-ddr5-tester"
				(path ""
					(reference "C287")
					(unit 1)
				)
			)
		)
	)
	(symbol
		(lib_id "antmicroCapacitors0402:C_100n_0402")
		(at 142.24 133.35 0)
		(mirror y)
		(unit 1)
		(exclude_from_sim no)
		(in_bom yes)
		(on_board yes)
		(dnp no)
		(property "Reference" "C228"
			(at 143.51 132.08 0)
			(effects
				(font
					(size 1.27 1.27)
				)
			)
		)
		(property "Value" "C_100n_0402"
			(at 121.92 143.51 0)
			(effects
				(font
					(size 1.27 1.27)
					(thickness 0.15)
				)
				(justify left bottom)
				(hide yes)
			)
		)
		(property "Footprint" "antmicro-footprints:C_0402_1005Metric"
			(at 121.92 146.05 0)
			(effects
				(font
					(size 1.27 1.27)
					(thickness 0.15)
				)
				(justify left bottom)
				(hide yes)
			)
		)
		(property "Datasheet" "https://www.murata.com/products/productdetail?partno=GRM155R61H104KE14%23"
			(at 121.92 148.59 0)
			(effects
				(font
					(size 1.27 1.27)
					(thickness 0.15)
				)
				(justify left bottom)
				(hide yes)
			)
		)
		(property "Description" ""
			(at 142.24 133.35 0)
			(effects
				(font
					(size 1.27 1.27)
				)
				(hide yes)
			)
		)
		(property "Manufacturer" "Murata"
			(at 121.92 153.67 0)
			(effects
				(font
					(size 1.27 1.27)
					(thickness 0.15)
				)
				(justify left bottom)
				(hide yes)
			)
		)
		(property "MPN" "GRM155R61H104KE14D"
			(at 121.92 151.13 0)
			(effects
				(font
					(size 1.27 1.27)
					(thickness 0.15)
				)
				(justify left bottom)
				(hide yes)
			)
		)
		(property "Val" "100n"
			(at 136.525 132.08 0)
			(effects
				(font
					(size 1.27 1.27)
					(thickness 0.15)
				)
			)
		)
		(property "License" "Apache-2.0"
			(at 121.92 156.21 0)
			(effects
				(font
					(size 1.27 1.27)
					(thickness 0.15)
				)
				(justify left bottom)
				(hide yes)
			)
		)
		(property "Author" "Antmicro"
			(at 121.92 158.75 0)
			(effects
				(font
					(size 1.27 1.27)
					(thickness 0.15)
				)
				(justify left bottom)
				(hide yes)
			)
		)
		(property "Voltage" "50V"
			(at 121.92 161.29 0)
			(effects
				(font
					(size 1.27 1.27)
				)
				(justify left bottom)
				(hide yes)
			)
		)
		(property "Dielectric" "X5R"
			(at 121.92 163.83 0)
			(effects
				(font
					(size 1.27 1.27)
				)
				(justify left bottom)
				(hide yes)
			)
		)
		(pin "1"
		)
		(pin "2"
		)
		(instances
			(project "data-center-rdimm-ddr5-tester"
				(path ""
					(reference "C228")
					(unit 1)
				)
			)
		)
	)
	(symbol
		(lib_id "antmicroCapacitors0402:C_100n_0402")
		(at 325.12 78.74 0)
		(mirror y)
		(unit 1)
		(exclude_from_sim no)
		(in_bom yes)
		(on_board yes)
		(dnp no)
		(property "Reference" "C244"
			(at 318.77 77.47 0)
			(effects
				(font
					(size 1.27 1.27)
				)
			)
		)
		(property "Value" "C_100n_0402"
			(at 304.8 88.9 0)
			(effects
				(font
					(size 1.27 1.27)
					(thickness 0.15)
				)
				(justify left bottom)
				(hide yes)
			)
		)
		(property "Footprint" "antmicro-footprints:C_0402_1005Metric"
			(at 304.8 91.44 0)
			(effects
				(font
					(size 1.27 1.27)
					(thickness 0.15)
				)
				(justify left bottom)
				(hide yes)
			)
		)
		(property "Datasheet" "https://www.murata.com/products/productdetail?partno=GRM155R61H104KE14%23"
			(at 304.8 93.98 0)
			(effects
				(font
					(size 1.27 1.27)
					(thickness 0.15)
				)
				(justify left bottom)
				(hide yes)
			)
		)
		(property "Description" ""
			(at 325.12 78.74 0)
			(effects
				(font
					(size 1.27 1.27)
				)
				(hide yes)
			)
		)
		(property "Manufacturer" "Murata"
			(at 304.8 99.06 0)
			(effects
				(font
					(size 1.27 1.27)
					(thickness 0.15)
				)
				(justify left bottom)
				(hide yes)
			)
		)
		(property "MPN" "GRM155R61H104KE14D"
			(at 304.8 96.52 0)
			(effects
				(font
					(size 1.27 1.27)
					(thickness 0.15)
				)
				(justify left bottom)
				(hide yes)
			)
		)
		(property "Val" "100n"
			(at 318.77 80.01 0)
			(effects
				(font
					(size 1.27 1.27)
					(thickness 0.15)
				)
			)
		)
		(property "License" "Apache-2.0"
			(at 304.8 101.6 0)
			(effects
				(font
					(size 1.27 1.27)
					(thickness 0.15)
				)
				(justify left bottom)
				(hide yes)
			)
		)
		(property "Author" "Antmicro"
			(at 304.8 104.14 0)
			(effects
				(font
					(size 1.27 1.27)
					(thickness 0.15)
				)
				(justify left bottom)
				(hide yes)
			)
		)
		(property "Voltage" "50V"
			(at 304.8 106.68 0)
			(effects
				(font
					(size 1.27 1.27)
				)
				(justify left bottom)
				(hide yes)
			)
		)
		(property "Dielectric" "X5R"
			(at 304.8 109.22 0)
			(effects
				(font
					(size 1.27 1.27)
				)
				(justify left bottom)
				(hide yes)
			)
		)
		(pin "1"
		)
		(pin "2"
		)
		(instances
			(project "data-center-rdimm-ddr5-tester"
				(path ""
					(reference "C244")
					(unit 1)
				)
			)
		)
	)
	(symbol
		(lib_id "antmicroCapacitors0402:C_100n_0402")
		(at 233.68 173.99 90)
		(mirror x)
		(unit 1)
		(exclude_from_sim no)
		(in_bom yes)
		(on_board yes)
		(dnp no)
		(property "Reference" "C286"
			(at 234.95 180.34 0)
			(effects
				(font
					(size 1.27 1.27)
					(thickness 0.15)
				)
			)
		)
		(property "Value" "C_100n_0402"
			(at 243.84 194.31 0)
			(effects
				(font
					(size 1.27 1.27)
					(thickness 0.15)
				)
				(justify left bottom)
				(hide yes)
			)
		)
		(property "Footprint" "antmicro-footprints:C_0402_1005Metric"
			(at 246.38 194.31 0)
			(effects
				(font
					(size 1.27 1.27)
					(thickness 0.15)
				)
				(justify left bottom)
				(hide yes)
			)
		)
		(property "Datasheet" "https://www.murata.com/products/productdetail?partno=GRM155R61H104KE14%23"
			(at 248.92 194.31 0)
			(effects
				(font
					(size 1.27 1.27)
					(thickness 0.15)
				)
				(justify left bottom)
				(hide yes)
			)
		)
		(property "Description" ""
			(at 233.68 173.99 0)
			(effects
				(font
					(size 1.27 1.27)
				)
				(hide yes)
			)
		)
		(property "MPN" "GRM155R61H104KE14D"
			(at 251.46 194.31 0)
			(effects
				(font
					(size 1.27 1.27)
					(thickness 0.15)
				)
				(justify left bottom)
				(hide yes)
			)
		)
		(property "Manufacturer" "Murata"
			(at 254 194.31 0)
			(effects
				(font
					(size 1.27 1.27)
					(thickness 0.15)
				)
				(justify left bottom)
				(hide yes)
			)
		)
		(property "License" "Apache-2.0"
			(at 256.54 194.31 0)
			(effects
				(font
					(size 1.27 1.27)
					(thickness 0.15)
				)
				(justify left bottom)
				(hide yes)
			)
		)
		(property "Author" "Antmicro"
			(at 259.08 194.31 0)
			(effects
				(font
					(size 1.27 1.27)
					(thickness 0.15)
				)
				(justify left bottom)
				(hide yes)
			)
		)
		(property "Val" "100n"
			(at 236.22 170.18 0)
			(effects
				(font
					(size 1.27 1.27)
					(thickness 0.15)
				)
				(justify left bottom)
			)
		)
		(property "Voltage" "50V"
			(at 261.62 194.31 0)
			(effects
				(font
					(size 1.27 1.27)
				)
				(justify left bottom)
				(hide yes)
			)
		)
		(property "Dielectric" "X5R"
			(at 264.16 194.31 0)
			(effects
				(font
					(size 1.27 1.27)
				)
				(justify left bottom)
				(hide yes)
			)
		)
		(property "Public" ""
			(at 266.7 194.31 0)
			(effects
				(font
					(size 1.27 1.27)
				)
				(justify left bottom)
				(hide yes)
			)
		)
		(pin "2"
		)
		(pin "1"
		)
		(instances
			(project "data-center-rdimm-ddr5-tester"
				(path ""
					(reference "C286")
					(unit 1)
				)
			)
		)
	)
	(symbol
		(lib_id "antmicroTestPoints:TP_0.75mm_SMD")
		(at 303.53 209.55 180)
		(unit 1)
		(exclude_from_sim no)
		(in_bom no)
		(on_board yes)
		(dnp no)
		(property "Reference" "TP6"
			(at 297.18 209.55 0)
			(effects
				(font
					(size 1.27 1.27)
					(thickness 0.15)
				)
			)
		)
		(property "Value" "TP_0.75mm_SMD"
			(at 293.37 205.74 0)
			(effects
				(font
					(size 1.27 1.27)
					(thickness 0.15)
				)
				(justify left bottom)
				(hide yes)
			)
		)
		(property "Footprint" "antmicro-footprints:TP_SMD_0.75mm"
			(at 293.37 203.2 0)
			(effects
				(font
					(size 1.27 1.27)
					(thickness 0.15)
				)
				(justify left bottom)
				(hide yes)
			)
		)
		(property "Datasheet" ""
			(at 285.75 196.85 0)
			(effects
				(font
					(size 1.27 1.27)
					(thickness 0.15)
				)
				(justify left bottom)
				(hide yes)
			)
		)
		(property "Description" ""
			(at 303.53 209.55 0)
			(effects
				(font
					(size 1.27 1.27)
				)
				(hide yes)
			)
		)
		(property "MPN" ""
			(at 292.735 198.12 0)
			(effects
				(font
					(size 1.27 1.27)
					(thickness 0.15)
				)
				(justify left bottom)
				(hide yes)
			)
		)
		(property "Manufacturer" ""
			(at 292.735 203.2 0)
			(effects
				(font
					(size 1.27 1.27)
					(thickness 0.15)
				)
				(justify left bottom)
				(hide yes)
			)
		)
		(property "Author" "Antmicro"
			(at 293.37 200.66 0)
			(effects
				(font
					(size 1.27 1.27)
					(thickness 0.15)
				)
				(justify left bottom)
				(hide yes)
			)
		)
		(property "License" "Apache-2.0"
			(at 293.37 198.12 0)
			(effects
				(font
					(size 1.27 1.27)
					(thickness 0.15)
				)
				(justify left bottom)
				(hide yes)
			)
		)
		(pin "1"
		)
		(instances
			(project "data-center-rdimm-ddr5-tester"
				(path ""
					(reference "TP6")
					(unit 1)
				)
			)
		)
	)
	(symbol
		(lib_id "antmicroCapacitors0402:C_100n_0402")
		(at 328.93 81.28 0)
		(mirror y)
		(unit 1)
		(exclude_from_sim no)
		(in_bom yes)
		(on_board yes)
		(dnp no)
		(property "Reference" "C245"
			(at 330.2 80.01 0)
			(effects
				(font
					(size 1.27 1.27)
				)
			)
		)
		(property "Value" "C_100n_0402"
			(at 308.61 91.44 0)
			(effects
				(font
					(size 1.27 1.27)
					(thickness 0.15)
				)
				(justify left bottom)
				(hide yes)
			)
		)
		(property "Footprint" "antmicro-footprints:C_0402_1005Metric"
			(at 308.61 93.98 0)
			(effects
				(font
					(size 1.27 1.27)
					(thickness 0.15)
				)
				(justify left bottom)
				(hide yes)
			)
		)
		(property "Datasheet" "https://www.murata.com/products/productdetail?partno=GRM155R61H104KE14%23"
			(at 308.61 96.52 0)
			(effects
				(font
					(size 1.27 1.27)
					(thickness 0.15)
				)
				(justify left bottom)
				(hide yes)
			)
		)
		(property "Description" ""
			(at 328.93 81.28 0)
			(effects
				(font
					(size 1.27 1.27)
				)
				(hide yes)
			)
		)
		(property "Manufacturer" "Murata"
			(at 308.61 101.6 0)
			(effects
				(font
					(size 1.27 1.27)
					(thickness 0.15)
				)
				(justify left bottom)
				(hide yes)
			)
		)
		(property "MPN" "GRM155R61H104KE14D"
			(at 308.61 99.06 0)
			(effects
				(font
					(size 1.27 1.27)
					(thickness 0.15)
				)
				(justify left bottom)
				(hide yes)
			)
		)
		(property "Val" "100n"
			(at 330.2 82.55 0)
			(effects
				(font
					(size 1.27 1.27)
					(thickness 0.15)
				)
			)
		)
		(property "License" "Apache-2.0"
			(at 308.61 104.14 0)
			(effects
				(font
					(size 1.27 1.27)
					(thickness 0.15)
				)
				(justify left bottom)
				(hide yes)
			)
		)
		(property "Author" "Antmicro"
			(at 308.61 106.68 0)
			(effects
				(font
					(size 1.27 1.27)
					(thickness 0.15)
				)
				(justify left bottom)
				(hide yes)
			)
		)
		(property "Voltage" "50V"
			(at 308.61 109.22 0)
			(effects
				(font
					(size 1.27 1.27)
				)
				(justify left bottom)
				(hide yes)
			)
		)
		(property "Dielectric" "X5R"
			(at 308.61 111.76 0)
			(effects
				(font
					(size 1.27 1.27)
				)
				(justify left bottom)
				(hide yes)
			)
		)
		(pin "1"
		)
		(pin "2"
		)
		(instances
			(project "data-center-rdimm-ddr5-tester"
				(path ""
					(reference "C245")
					(unit 1)
				)
			)
		)
	)
	(symbol
		(lib_id "antmicroCapacitors0402:C_100n_0402")
		(at 142.24 148.59 0)
		(mirror y)
		(unit 1)
		(exclude_from_sim no)
		(in_bom yes)
		(on_board yes)
		(dnp no)
		(property "Reference" "C232"
			(at 143.51 147.32 0)
			(effects
				(font
					(size 1.27 1.27)
				)
			)
		)
		(property "Value" "C_100n_0402"
			(at 121.92 158.75 0)
			(effects
				(font
					(size 1.27 1.27)
					(thickness 0.15)
				)
				(justify left bottom)
				(hide yes)
			)
		)
		(property "Footprint" "antmicro-footprints:C_0402_1005Metric"
			(at 121.92 161.29 0)
			(effects
				(font
					(size 1.27 1.27)
					(thickness 0.15)
				)
				(justify left bottom)
				(hide yes)
			)
		)
		(property "Datasheet" "https://www.murata.com/products/productdetail?partno=GRM155R61H104KE14%23"
			(at 121.92 163.83 0)
			(effects
				(font
					(size 1.27 1.27)
					(thickness 0.15)
				)
				(justify left bottom)
				(hide yes)
			)
		)
		(property "Description" ""
			(at 142.24 148.59 0)
			(effects
				(font
					(size 1.27 1.27)
				)
				(hide yes)
			)
		)
		(property "Manufacturer" "Murata"
			(at 121.92 168.91 0)
			(effects
				(font
					(size 1.27 1.27)
					(thickness 0.15)
				)
				(justify left bottom)
				(hide yes)
			)
		)
		(property "MPN" "GRM155R61H104KE14D"
			(at 121.92 166.37 0)
			(effects
				(font
					(size 1.27 1.27)
					(thickness 0.15)
				)
				(justify left bottom)
				(hide yes)
			)
		)
		(property "Val" "100n"
			(at 136.525 147.32 0)
			(effects
				(font
					(size 1.27 1.27)
					(thickness 0.15)
				)
			)
		)
		(property "License" "Apache-2.0"
			(at 121.92 171.45 0)
			(effects
				(font
					(size 1.27 1.27)
					(thickness 0.15)
				)
				(justify left bottom)
				(hide yes)
			)
		)
		(property "Author" "Antmicro"
			(at 121.92 173.99 0)
			(effects
				(font
					(size 1.27 1.27)
					(thickness 0.15)
				)
				(justify left bottom)
				(hide yes)
			)
		)
		(property "Voltage" "50V"
			(at 121.92 176.53 0)
			(effects
				(font
					(size 1.27 1.27)
				)
				(justify left bottom)
				(hide yes)
			)
		)
		(property "Dielectric" "X5R"
			(at 121.92 179.07 0)
			(effects
				(font
					(size 1.27 1.27)
				)
				(justify left bottom)
				(hide yes)
			)
		)
		(pin "1"
		)
		(pin "2"
		)
		(instances
			(project "data-center-rdimm-ddr5-tester"
				(path ""
					(reference "C232")
					(unit 1)
				)
			)
		)
	)
	(symbol
		(lib_id "antmicroCapacitors0402:C_10n_0402")
		(at 137.16 204.47 0)
		(unit 1)
		(exclude_from_sim no)
		(in_bom yes)
		(on_board yes)
		(dnp no)
		(property "Reference" "C258"
			(at 143.51 208.28 0)
			(effects
				(font
					(size 1.27 1.27)
					(thickness 0.15)
				)
			)
		)
		(property "Value" "C_10n_0402"
			(at 157.48 214.63 0)
			(effects
				(font
					(size 1.27 1.27)
					(thickness 0.15)
				)
				(justify left bottom)
				(hide yes)
			)
		)
		(property "Footprint" "antmicro-footprints:C_0402_1005Metric"
			(at 157.48 217.17 0)
			(effects
				(font
					(size 1.27 1.27)
					(thickness 0.15)
				)
				(justify left bottom)
				(hide yes)
			)
		)
		(property "Datasheet" "https://www.murata.com/products/productdetail?partno=GRM155R71H103KA88%23"
			(at 157.48 219.71 0)
			(effects
				(font
					(size 1.27 1.27)
					(thickness 0.15)
				)
				(justify left bottom)
				(hide yes)
			)
		)
		(property "Description" ""
			(at 137.16 204.47 0)
			(effects
				(font
					(size 1.27 1.27)
				)
				(hide yes)
			)
		)
		(property "MPN" "GRM155R71H103KA88D"
			(at 157.48 222.25 0)
			(effects
				(font
					(size 1.27 1.27)
					(thickness 0.15)
				)
				(justify left bottom)
				(hide yes)
			)
		)
		(property "Manufacturer" "Murata"
			(at 157.48 224.79 0)
			(effects
				(font
					(size 1.27 1.27)
					(thickness 0.15)
				)
				(justify left bottom)
				(hide yes)
			)
		)
		(property "License" "Apache-2.0"
			(at 157.48 227.33 0)
			(effects
				(font
					(size 1.27 1.27)
					(thickness 0.15)
				)
				(justify left bottom)
				(hide yes)
			)
		)
		(property "Author" "Antmicro"
			(at 157.48 229.87 0)
			(effects
				(font
					(size 1.27 1.27)
					(thickness 0.15)
				)
				(justify left bottom)
				(hide yes)
			)
		)
		(property "Val" "10n"
			(at 135.255 203.2 0)
			(effects
				(font
					(size 1.27 1.27)
					(thickness 0.15)
				)
			)
		)
		(property "Voltage" "50V"
			(at 157.48 232.41 0)
			(effects
				(font
					(size 1.27 1.27)
				)
				(justify left bottom)
				(hide yes)
			)
		)
		(property "Dielectric" "X7R"
			(at 157.48 234.95 0)
			(effects
				(font
					(size 1.27 1.27)
				)
				(justify left bottom)
				(hide yes)
			)
		)
		(pin "1"
		)
		(pin "2"
		)
		(instances
			(project "data-center-rdimm-ddr5-tester"
				(path ""
					(reference "C258")
					(unit 1)
				)
			)
		)
	)
	(symbol
		(lib_id "antmicroCapacitors0402:C_100n_0402")
		(at 328.93 57.15 0)
		(mirror y)
		(unit 1)
		(exclude_from_sim no)
		(in_bom yes)
		(on_board yes)
		(dnp no)
		(property "Reference" "C276"
			(at 330.2 55.88 0)
			(effects
				(font
					(size 1.27 1.27)
				)
			)
		)
		(property "Value" "C_100n_0402"
			(at 308.61 67.31 0)
			(effects
				(font
					(size 1.27 1.27)
					(thickness 0.15)
				)
				(justify left bottom)
				(hide yes)
			)
		)
		(property "Footprint" "antmicro-footprints:C_0402_1005Metric"
			(at 308.61 69.85 0)
			(effects
				(font
					(size 1.27 1.27)
					(thickness 0.15)
				)
				(justify left bottom)
				(hide yes)
			)
		)
		(property "Datasheet" "https://www.murata.com/products/productdetail?partno=GRM155R61H104KE14%23"
			(at 308.61 72.39 0)
			(effects
				(font
					(size 1.27 1.27)
					(thickness 0.15)
				)
				(justify left bottom)
				(hide yes)
			)
		)
		(property "Description" ""
			(at 328.93 57.15 0)
			(effects
				(font
					(size 1.27 1.27)
				)
				(hide yes)
			)
		)
		(property "Manufacturer" "Murata"
			(at 308.61 77.47 0)
			(effects
				(font
					(size 1.27 1.27)
					(thickness 0.15)
				)
				(justify left bottom)
				(hide yes)
			)
		)
		(property "MPN" "GRM155R61H104KE14D"
			(at 308.61 74.93 0)
			(effects
				(font
					(size 1.27 1.27)
					(thickness 0.15)
				)
				(justify left bottom)
				(hide yes)
			)
		)
		(property "Val" "100n"
			(at 330.2 58.42 0)
			(effects
				(font
					(size 1.27 1.27)
					(thickness 0.15)
				)
			)
		)
		(property "License" "Apache-2.0"
			(at 308.61 80.01 0)
			(effects
				(font
					(size 1.27 1.27)
					(thickness 0.15)
				)
				(justify left bottom)
				(hide yes)
			)
		)
		(property "Author" "Antmicro"
			(at 308.61 82.55 0)
			(effects
				(font
					(size 1.27 1.27)
					(thickness 0.15)
				)
				(justify left bottom)
				(hide yes)
			)
		)
		(property "Voltage" "50V"
			(at 308.61 85.09 0)
			(effects
				(font
					(size 1.27 1.27)
				)
				(justify left bottom)
				(hide yes)
			)
		)
		(property "Dielectric" "X5R"
			(at 308.61 87.63 0)
			(effects
				(font
					(size 1.27 1.27)
				)
				(justify left bottom)
				(hide yes)
			)
		)
		(pin "1"
		)
		(pin "2"
		)
		(instances
			(project "data-center-rdimm-ddr5-tester"
				(path ""
					(reference "C276")
					(unit 1)
				)
			)
		)
	)
	(symbol
		(lib_id "antmicroCapacitors0402:C_10n_0402")
		(at 137.16 209.55 0)
		(unit 1)
		(exclude_from_sim no)
		(in_bom yes)
		(on_board yes)
		(dnp no)
		(property "Reference" "C222"
			(at 143.51 203.2 0)
			(effects
				(font
					(size 1.27 1.27)
					(thickness 0.15)
				)
			)
		)
		(property "Value" "C_10n_0402"
			(at 157.48 219.71 0)
			(effects
				(font
					(size 1.27 1.27)
					(thickness 0.15)
				)
				(justify left bottom)
				(hide yes)
			)
		)
		(property "Footprint" "antmicro-footprints:C_0402_1005Metric"
			(at 157.48 222.25 0)
			(effects
				(font
					(size 1.27 1.27)
					(thickness 0.15)
				)
				(justify left bottom)
				(hide yes)
			)
		)
		(property "Datasheet" "https://www.murata.com/products/productdetail?partno=GRM155R71H103KA88%23"
			(at 157.48 224.79 0)
			(effects
				(font
					(size 1.27 1.27)
					(thickness 0.15)
				)
				(justify left bottom)
				(hide yes)
			)
		)
		(property "Description" ""
			(at 137.16 209.55 0)
			(effects
				(font
					(size 1.27 1.27)
				)
				(hide yes)
			)
		)
		(property "MPN" "GRM155R71H103KA88D"
			(at 157.48 227.33 0)
			(effects
				(font
					(size 1.27 1.27)
					(thickness 0.15)
				)
				(justify left bottom)
				(hide yes)
			)
		)
		(property "Manufacturer" "Murata"
			(at 157.48 229.87 0)
			(effects
				(font
					(size 1.27 1.27)
					(thickness 0.15)
				)
				(justify left bottom)
				(hide yes)
			)
		)
		(property "License" "Apache-2.0"
			(at 157.48 232.41 0)
			(effects
				(font
					(size 1.27 1.27)
					(thickness 0.15)
				)
				(justify left bottom)
				(hide yes)
			)
		)
		(property "Author" "Antmicro"
			(at 157.48 234.95 0)
			(effects
				(font
					(size 1.27 1.27)
					(thickness 0.15)
				)
				(justify left bottom)
				(hide yes)
			)
		)
		(property "Val" "10n"
			(at 135.89 208.28 0)
			(effects
				(font
					(size 1.27 1.27)
					(thickness 0.15)
				)
			)
		)
		(property "Voltage" "50V"
			(at 157.48 237.49 0)
			(effects
				(font
					(size 1.27 1.27)
				)
				(justify left bottom)
				(hide yes)
			)
		)
		(property "Dielectric" "X7R"
			(at 157.48 240.03 0)
			(effects
				(font
					(size 1.27 1.27)
				)
				(justify left bottom)
				(hide yes)
			)
		)
		(pin "1"
		)
		(pin "2"
		)
		(instances
			(project "data-center-rdimm-ddr5-tester"
				(path ""
					(reference "C222")
					(unit 1)
				)
			)
		)
	)
	(symbol
		(lib_id "antmicroCapacitors0402:C_100n_0402")
		(at 142.24 114.3 0)
		(mirror y)
		(unit 1)
		(exclude_from_sim no)
		(in_bom yes)
		(on_board yes)
		(dnp no)
		(property "Reference" "C226"
			(at 143.51 113.03 0)
			(effects
				(font
					(size 1.27 1.27)
				)
			)
		)
		(property "Value" "C_100n_0402"
			(at 121.92 124.46 0)
			(effects
				(font
					(size 1.27 1.27)
					(thickness 0.15)
				)
				(justify left bottom)
				(hide yes)
			)
		)
		(property "Footprint" "antmicro-footprints:C_0402_1005Metric"
			(at 121.92 127 0)
			(effects
				(font
					(size 1.27 1.27)
					(thickness 0.15)
				)
				(justify left bottom)
				(hide yes)
			)
		)
		(property "Datasheet" "https://www.murata.com/products/productdetail?partno=GRM155R61H104KE14%23"
			(at 121.92 129.54 0)
			(effects
				(font
					(size 1.27 1.27)
					(thickness 0.15)
				)
				(justify left bottom)
				(hide yes)
			)
		)
		(property "Description" ""
			(at 142.24 114.3 0)
			(effects
				(font
					(size 1.27 1.27)
				)
				(hide yes)
			)
		)
		(property "Manufacturer" "Murata"
			(at 121.92 134.62 0)
			(effects
				(font
					(size 1.27 1.27)
					(thickness 0.15)
				)
				(justify left bottom)
				(hide yes)
			)
		)
		(property "MPN" "GRM155R61H104KE14D"
			(at 121.92 132.08 0)
			(effects
				(font
					(size 1.27 1.27)
					(thickness 0.15)
				)
				(justify left bottom)
				(hide yes)
			)
		)
		(property "Val" "100n"
			(at 136.525 113.03 0)
			(effects
				(font
					(size 1.27 1.27)
					(thickness 0.15)
				)
			)
		)
		(property "License" "Apache-2.0"
			(at 121.92 137.16 0)
			(effects
				(font
					(size 1.27 1.27)
					(thickness 0.15)
				)
				(justify left bottom)
				(hide yes)
			)
		)
		(property "Author" "Antmicro"
			(at 121.92 139.7 0)
			(effects
				(font
					(size 1.27 1.27)
					(thickness 0.15)
				)
				(justify left bottom)
				(hide yes)
			)
		)
		(property "Voltage" "50V"
			(at 121.92 142.24 0)
			(effects
				(font
					(size 1.27 1.27)
				)
				(justify left bottom)
				(hide yes)
			)
		)
		(property "Dielectric" "X5R"
			(at 121.92 144.78 0)
			(effects
				(font
					(size 1.27 1.27)
				)
				(justify left bottom)
				(hide yes)
			)
		)
		(pin "1"
		)
		(pin "2"
		)
		(instances
			(project "data-center-rdimm-ddr5-tester"
				(path ""
					(reference "C226")
					(unit 1)
				)
			)
		)
	)
	(symbol
		(lib_id "antmicropower:GND")
		(at 223.52 184.15 0)
		(mirror y)
		(unit 1)
		(exclude_from_sim no)
		(in_bom yes)
		(on_board yes)
		(dnp no)
		(property "Reference" "#PWR070"
			(at 214.63 186.69 0)
			(effects
				(font
					(size 1.27 1.27)
					(thickness 0.15)
				)
				(justify left bottom)
				(hide yes)
			)
		)
		(property "Value" "GND"
			(at 223.52 187.96 0)
			(effects
				(font
					(size 1.27 1.27)
					(thickness 0.15)
				)
			)
		)
		(property "Footprint" ""
			(at 214.63 191.77 0)
			(effects
				(font
					(size 1.27 1.27)
					(thickness 0.15)
				)
				(justify left bottom)
				(hide yes)
			)
		)
		(property "Datasheet" ""
			(at 214.63 196.85 0)
			(effects
				(font
					(size 1.27 1.27)
					(thickness 0.15)
				)
				(justify left bottom)
				(hide yes)
			)
		)
		(property "Description" ""
			(at 223.52 184.15 0)
			(effects
				(font
					(size 1.27 1.27)
				)
				(hide yes)
			)
		)
		(property "Author" "Antmicro"
			(at 214.63 191.77 0)
			(effects
				(font
					(size 1.27 1.27)
					(thickness 0.15)
				)
				(justify left bottom)
				(hide yes)
			)
		)
		(property "License" "Apache-2.0"
			(at 214.63 194.31 0)
			(effects
				(font
					(size 1.27 1.27)
					(thickness 0.15)
				)
				(justify left bottom)
				(hide yes)
			)
		)
		(pin "1"
		)
		(instances
			(project "data-center-rdimm-ddr5-tester"
				(path ""
					(reference "#PWR070")
					(unit 1)
				)
			)
		)
	)
	(symbol
		(lib_id "antmicroCapacitors0402:C_100n_0402")
		(at 142.24 119.38 0)
		(mirror y)
		(unit 1)
		(exclude_from_sim no)
		(in_bom yes)
		(on_board yes)
		(dnp no)
		(property "Reference" "C230"
			(at 143.51 118.11 0)
			(effects
				(font
					(size 1.27 1.27)
				)
			)
		)
		(property "Value" "C_100n_0402"
			(at 121.92 129.54 0)
			(effects
				(font
					(size 1.27 1.27)
					(thickness 0.15)
				)
				(justify left bottom)
				(hide yes)
			)
		)
		(property "Footprint" "antmicro-footprints:C_0402_1005Metric"
			(at 121.92 132.08 0)
			(effects
				(font
					(size 1.27 1.27)
					(thickness 0.15)
				)
				(justify left bottom)
				(hide yes)
			)
		)
		(property "Datasheet" "https://www.murata.com/products/productdetail?partno=GRM155R61H104KE14%23"
			(at 121.92 134.62 0)
			(effects
				(font
					(size 1.27 1.27)
					(thickness 0.15)
				)
				(justify left bottom)
				(hide yes)
			)
		)
		(property "Description" ""
			(at 142.24 119.38 0)
			(effects
				(font
					(size 1.27 1.27)
				)
				(hide yes)
			)
		)
		(property "Manufacturer" "Murata"
			(at 121.92 139.7 0)
			(effects
				(font
					(size 1.27 1.27)
					(thickness 0.15)
				)
				(justify left bottom)
				(hide yes)
			)
		)
		(property "MPN" "GRM155R61H104KE14D"
			(at 121.92 137.16 0)
			(effects
				(font
					(size 1.27 1.27)
					(thickness 0.15)
				)
				(justify left bottom)
				(hide yes)
			)
		)
		(property "Val" "100n"
			(at 136.525 118.11 0)
			(effects
				(font
					(size 1.27 1.27)
					(thickness 0.15)
				)
			)
		)
		(property "License" "Apache-2.0"
			(at 121.92 142.24 0)
			(effects
				(font
					(size 1.27 1.27)
					(thickness 0.15)
				)
				(justify left bottom)
				(hide yes)
			)
		)
		(property "Author" "Antmicro"
			(at 121.92 144.78 0)
			(effects
				(font
					(size 1.27 1.27)
					(thickness 0.15)
				)
				(justify left bottom)
				(hide yes)
			)
		)
		(property "Voltage" "50V"
			(at 121.92 147.32 0)
			(effects
				(font
					(size 1.27 1.27)
				)
				(justify left bottom)
				(hide yes)
			)
		)
		(property "Dielectric" "X5R"
			(at 121.92 149.86 0)
			(effects
				(font
					(size 1.27 1.27)
				)
				(justify left bottom)
				(hide yes)
			)
		)
		(pin "1"
		)
		(pin "2"
		)
		(instances
			(project "data-center-rdimm-ddr5-tester"
				(path ""
					(reference "C230")
					(unit 1)
				)
			)
		)
	)
	(symbol
		(lib_id "antmicroCapacitors0402:C_100n_0402")
		(at 137.16 99.06 0)
		(mirror x)
		(unit 1)
		(exclude_from_sim no)
		(in_bom yes)
		(on_board yes)
		(dnp no)
		(property "Reference" "C250"
			(at 143.51 97.79 0)
			(effects
				(font
					(size 1.27 1.27)
				)
			)
		)
		(property "Value" "C_100n_0402"
			(at 157.48 88.9 0)
			(effects
				(font
					(size 1.27 1.27)
					(thickness 0.15)
				)
				(justify left bottom)
				(hide yes)
			)
		)
		(property "Footprint" "antmicro-footprints:C_0402_1005Metric"
			(at 157.48 86.36 0)
			(effects
				(font
					(size 1.27 1.27)
					(thickness 0.15)
				)
				(justify left bottom)
				(hide yes)
			)
		)
		(property "Datasheet" "https://www.murata.com/products/productdetail?partno=GRM155R61H104KE14%23"
			(at 157.48 83.82 0)
			(effects
				(font
					(size 1.27 1.27)
					(thickness 0.15)
				)
				(justify left bottom)
				(hide yes)
			)
		)
		(property "Description" ""
			(at 137.16 99.06 0)
			(effects
				(font
					(size 1.27 1.27)
				)
				(hide yes)
			)
		)
		(property "Manufacturer" "Murata"
			(at 157.48 78.74 0)
			(effects
				(font
					(size 1.27 1.27)
					(thickness 0.15)
				)
				(justify left bottom)
				(hide yes)
			)
		)
		(property "MPN" "GRM155R61H104KE14D"
			(at 157.48 81.28 0)
			(effects
				(font
					(size 1.27 1.27)
					(thickness 0.15)
				)
				(justify left bottom)
				(hide yes)
			)
		)
		(property "Val" "100n"
			(at 136.525 97.79 0)
			(effects
				(font
					(size 1.27 1.27)
					(thickness 0.15)
				)
			)
		)
		(property "License" "Apache-2.0"
			(at 157.48 76.2 0)
			(effects
				(font
					(size 1.27 1.27)
					(thickness 0.15)
				)
				(justify left bottom)
				(hide yes)
			)
		)
		(property "Author" "Antmicro"
			(at 157.48 73.66 0)
			(effects
				(font
					(size 1.27 1.27)
					(thickness 0.15)
				)
				(justify left bottom)
				(hide yes)
			)
		)
		(property "Voltage" "50V"
			(at 157.48 71.12 0)
			(effects
				(font
					(size 1.27 1.27)
				)
				(justify left bottom)
				(hide yes)
			)
		)
		(property "Dielectric" "X5R"
			(at 157.48 68.58 0)
			(effects
				(font
					(size 1.27 1.27)
				)
				(justify left bottom)
				(hide yes)
			)
		)
		(pin "1"
		)
		(pin "2"
		)
		(instances
			(project "data-center-rdimm-ddr5-tester"
				(path ""
					(reference "C250")
					(unit 1)
				)
			)
		)
	)
	(symbol
		(lib_id "antmicroCapacitors0402:C_100n_0402")
		(at 137.16 138.43 0)
		(mirror x)
		(unit 1)
		(exclude_from_sim no)
		(in_bom yes)
		(on_board yes)
		(dnp no)
		(property "Reference" "C233"
			(at 143.51 137.16 0)
			(effects
				(font
					(size 1.27 1.27)
				)
			)
		)
		(property "Value" "C_100n_0402"
			(at 157.48 128.27 0)
			(effects
				(font
					(size 1.27 1.27)
					(thickness 0.15)
				)
				(justify left bottom)
				(hide yes)
			)
		)
		(property "Footprint" "antmicro-footprints:C_0402_1005Metric"
			(at 157.48 125.73 0)
			(effects
				(font
					(size 1.27 1.27)
					(thickness 0.15)
				)
				(justify left bottom)
				(hide yes)
			)
		)
		(property "Datasheet" "https://www.murata.com/products/productdetail?partno=GRM155R61H104KE14%23"
			(at 157.48 123.19 0)
			(effects
				(font
					(size 1.27 1.27)
					(thickness 0.15)
				)
				(justify left bottom)
				(hide yes)
			)
		)
		(property "Description" ""
			(at 137.16 138.43 0)
			(effects
				(font
					(size 1.27 1.27)
				)
				(hide yes)
			)
		)
		(property "Manufacturer" "Murata"
			(at 157.48 118.11 0)
			(effects
				(font
					(size 1.27 1.27)
					(thickness 0.15)
				)
				(justify left bottom)
				(hide yes)
			)
		)
		(property "MPN" "GRM155R61H104KE14D"
			(at 157.48 120.65 0)
			(effects
				(font
					(size 1.27 1.27)
					(thickness 0.15)
				)
				(justify left bottom)
				(hide yes)
			)
		)
		(property "Val" "100n"
			(at 136.525 137.16 0)
			(effects
				(font
					(size 1.27 1.27)
					(thickness 0.15)
				)
			)
		)
		(property "License" "Apache-2.0"
			(at 157.48 115.57 0)
			(effects
				(font
					(size 1.27 1.27)
					(thickness 0.15)
				)
				(justify left bottom)
				(hide yes)
			)
		)
		(property "Author" "Antmicro"
			(at 157.48 113.03 0)
			(effects
				(font
					(size 1.27 1.27)
					(thickness 0.15)
				)
				(justify left bottom)
				(hide yes)
			)
		)
		(property "Voltage" "50V"
			(at 157.48 110.49 0)
			(effects
				(font
					(size 1.27 1.27)
				)
				(justify left bottom)
				(hide yes)
			)
		)
		(property "Dielectric" "X5R"
			(at 157.48 107.95 0)
			(effects
				(font
					(size 1.27 1.27)
				)
				(justify left bottom)
				(hide yes)
			)
		)
		(pin "1"
		)
		(pin "2"
		)
		(instances
			(project "data-center-rdimm-ddr5-tester"
				(path ""
					(reference "C233")
					(unit 1)
				)
			)
		)
	)
	(symbol
		(lib_id "antmicroCapacitors0402:C_100n_0402")
		(at 142.24 93.98 0)
		(mirror y)
		(unit 1)
		(exclude_from_sim no)
		(in_bom yes)
		(on_board yes)
		(dnp no)
		(property "Reference" "C255"
			(at 143.51 92.71 0)
			(effects
				(font
					(size 1.27 1.27)
				)
			)
		)
		(property "Value" "C_100n_0402"
			(at 121.92 104.14 0)
			(effects
				(font
					(size 1.27 1.27)
					(thickness 0.15)
				)
				(justify left bottom)
				(hide yes)
			)
		)
		(property "Footprint" "antmicro-footprints:C_0402_1005Metric"
			(at 121.92 106.68 0)
			(effects
				(font
					(size 1.27 1.27)
					(thickness 0.15)
				)
				(justify left bottom)
				(hide yes)
			)
		)
		(property "Datasheet" "https://www.murata.com/products/productdetail?partno=GRM155R61H104KE14%23"
			(at 121.92 109.22 0)
			(effects
				(font
					(size 1.27 1.27)
					(thickness 0.15)
				)
				(justify left bottom)
				(hide yes)
			)
		)
		(property "Description" ""
			(at 142.24 93.98 0)
			(effects
				(font
					(size 1.27 1.27)
				)
				(hide yes)
			)
		)
		(property "Manufacturer" "Murata"
			(at 121.92 114.3 0)
			(effects
				(font
					(size 1.27 1.27)
					(thickness 0.15)
				)
				(justify left bottom)
				(hide yes)
			)
		)
		(property "MPN" "GRM155R61H104KE14D"
			(at 121.92 111.76 0)
			(effects
				(font
					(size 1.27 1.27)
					(thickness 0.15)
				)
				(justify left bottom)
				(hide yes)
			)
		)
		(property "Val" "100n"
			(at 136.525 92.71 0)
			(effects
				(font
					(size 1.27 1.27)
					(thickness 0.15)
				)
			)
		)
		(property "License" "Apache-2.0"
			(at 121.92 116.84 0)
			(effects
				(font
					(size 1.27 1.27)
					(thickness 0.15)
				)
				(justify left bottom)
				(hide yes)
			)
		)
		(property "Author" "Antmicro"
			(at 121.92 119.38 0)
			(effects
				(font
					(size 1.27 1.27)
					(thickness 0.15)
				)
				(justify left bottom)
				(hide yes)
			)
		)
		(property "Voltage" "50V"
			(at 121.92 121.92 0)
			(effects
				(font
					(size 1.27 1.27)
				)
				(justify left bottom)
				(hide yes)
			)
		)
		(property "Dielectric" "X5R"
			(at 121.92 124.46 0)
			(effects
				(font
					(size 1.27 1.27)
				)
				(justify left bottom)
				(hide yes)
			)
		)
		(pin "1"
		)
		(pin "2"
		)
		(instances
			(project "data-center-rdimm-ddr5-tester"
				(path ""
					(reference "C255")
					(unit 1)
				)
			)
		)
	)
	(symbol
		(lib_id "antmicroCapacitors0402:C_100n_0402")
		(at 328.93 88.9 180)
		(unit 1)
		(exclude_from_sim no)
		(in_bom yes)
		(on_board yes)
		(dnp no)
		(property "Reference" "C306"
			(at 330.2 87.63 0)
			(effects
				(font
					(size 1.27 1.27)
				)
			)
		)
		(property "Value" "C_100n_0402"
			(at 308.61 78.74 0)
			(effects
				(font
					(size 1.27 1.27)
					(thickness 0.15)
				)
				(justify left bottom)
				(hide yes)
			)
		)
		(property "Footprint" "antmicro-footprints:C_0402_1005Metric"
			(at 308.61 76.2 0)
			(effects
				(font
					(size 1.27 1.27)
					(thickness 0.15)
				)
				(justify left bottom)
				(hide yes)
			)
		)
		(property "Datasheet" "https://www.murata.com/products/productdetail?partno=GRM155R61H104KE14%23"
			(at 308.61 73.66 0)
			(effects
				(font
					(size 1.27 1.27)
					(thickness 0.15)
				)
				(justify left bottom)
				(hide yes)
			)
		)
		(property "Description" ""
			(at 328.93 88.9 0)
			(effects
				(font
					(size 1.27 1.27)
				)
				(hide yes)
			)
		)
		(property "Manufacturer" "Murata"
			(at 308.61 68.58 0)
			(effects
				(font
					(size 1.27 1.27)
					(thickness 0.15)
				)
				(justify left bottom)
				(hide yes)
			)
		)
		(property "MPN" "GRM155R61H104KE14D"
			(at 308.61 71.12 0)
			(effects
				(font
					(size 1.27 1.27)
					(thickness 0.15)
				)
				(justify left bottom)
				(hide yes)
			)
		)
		(property "Val" "100n"
			(at 330.2 90.17 0)
			(effects
				(font
					(size 1.27 1.27)
					(thickness 0.15)
				)
			)
		)
		(property "License" "Apache-2.0"
			(at 308.61 66.04 0)
			(effects
				(font
					(size 1.27 1.27)
					(thickness 0.15)
				)
				(justify left bottom)
				(hide yes)
			)
		)
		(property "Author" "Antmicro"
			(at 308.61 63.5 0)
			(effects
				(font
					(size 1.27 1.27)
					(thickness 0.15)
				)
				(justify left bottom)
				(hide yes)
			)
		)
		(property "Voltage" "50V"
			(at 308.61 60.96 0)
			(effects
				(font
					(size 1.27 1.27)
				)
				(justify left bottom)
				(hide yes)
			)
		)
		(property "Dielectric" "X5R"
			(at 308.61 58.42 0)
			(effects
				(font
					(size 1.27 1.27)
				)
				(justify left bottom)
				(hide yes)
			)
		)
		(pin "1"
		)
		(pin "2"
		)
		(instances
			(project "data-center-rdimm-ddr5-tester"
				(path ""
					(reference "C306")
					(unit 1)
				)
			)
		)
	)
	(symbol
		(lib_id "antmicropower:GND")
		(at 308.61 241.3 0)
		(unit 1)
		(exclude_from_sim no)
		(in_bom yes)
		(on_board yes)
		(dnp no)
		(property "Reference" "#PWR0425"
			(at 317.5 243.84 0)
			(effects
				(font
					(size 1.27 1.27)
					(thickness 0.15)
				)
				(justify left bottom)
				(hide yes)
			)
		)
		(property "Value" "GND"
			(at 308.61 245.11 0)
			(effects
				(font
					(size 1.27 1.27)
					(thickness 0.15)
				)
			)
		)
		(property "Footprint" ""
			(at 317.5 248.92 0)
			(effects
				(font
					(size 1.27 1.27)
					(thickness 0.15)
				)
				(justify left bottom)
				(hide yes)
			)
		)
		(property "Datasheet" ""
			(at 317.5 254 0)
			(effects
				(font
					(size 1.27 1.27)
					(thickness 0.15)
				)
				(justify left bottom)
				(hide yes)
			)
		)
		(property "Description" ""
			(at 308.61 241.3 0)
			(effects
				(font
					(size 1.27 1.27)
				)
				(hide yes)
			)
		)
		(property "Author" "Antmicro"
			(at 317.5 248.92 0)
			(effects
				(font
					(size 1.27 1.27)
					(thickness 0.15)
				)
				(justify left bottom)
				(hide yes)
			)
		)
		(property "License" "Apache-2.0"
			(at 317.5 251.46 0)
			(effects
				(font
					(size 1.27 1.27)
					(thickness 0.15)
				)
				(justify left bottom)
				(hide yes)
			)
		)
		(pin "1"
		)
		(instances
			(project "data-center-rdimm-ddr5-tester"
				(path ""
					(reference "#PWR0425")
					(unit 1)
				)
			)
		)
	)
	(symbol
		(lib_id "antmicroCapacitors0402:C_100n_0402")
		(at 325.12 69.85 0)
		(mirror y)
		(unit 1)
		(exclude_from_sim no)
		(in_bom yes)
		(on_board yes)
		(dnp no)
		(property "Reference" "C292"
			(at 318.77 68.58 0)
			(effects
				(font
					(size 1.27 1.27)
				)
			)
		)
		(property "Value" "C_100n_0402"
			(at 304.8 80.01 0)
			(effects
				(font
					(size 1.27 1.27)
					(thickness 0.15)
				)
				(justify left bottom)
				(hide yes)
			)
		)
		(property "Footprint" "antmicro-footprints:C_0402_1005Metric"
			(at 304.8 82.55 0)
			(effects
				(font
					(size 1.27 1.27)
					(thickness 0.15)
				)
				(justify left bottom)
				(hide yes)
			)
		)
		(property "Datasheet" "https://www.murata.com/products/productdetail?partno=GRM155R61H104KE14%23"
			(at 304.8 85.09 0)
			(effects
				(font
					(size 1.27 1.27)
					(thickness 0.15)
				)
				(justify left bottom)
				(hide yes)
			)
		)
		(property "Description" ""
			(at 325.12 69.85 0)
			(effects
				(font
					(size 1.27 1.27)
				)
				(hide yes)
			)
		)
		(property "Manufacturer" "Murata"
			(at 304.8 90.17 0)
			(effects
				(font
					(size 1.27 1.27)
					(thickness 0.15)
				)
				(justify left bottom)
				(hide yes)
			)
		)
		(property "MPN" "GRM155R61H104KE14D"
			(at 304.8 87.63 0)
			(effects
				(font
					(size 1.27 1.27)
					(thickness 0.15)
				)
				(justify left bottom)
				(hide yes)
			)
		)
		(property "Val" "100n"
			(at 318.77 71.12 0)
			(effects
				(font
					(size 1.27 1.27)
					(thickness 0.15)
				)
			)
		)
		(property "License" "Apache-2.0"
			(at 304.8 92.71 0)
			(effects
				(font
					(size 1.27 1.27)
					(thickness 0.15)
				)
				(justify left bottom)
				(hide yes)
			)
		)
		(property "Author" "Antmicro"
			(at 304.8 95.25 0)
			(effects
				(font
					(size 1.27 1.27)
					(thickness 0.15)
				)
				(justify left bottom)
				(hide yes)
			)
		)
		(property "Voltage" "50V"
			(at 304.8 97.79 0)
			(effects
				(font
					(size 1.27 1.27)
				)
				(justify left bottom)
				(hide yes)
			)
		)
		(property "Dielectric" "X5R"
			(at 304.8 100.33 0)
			(effects
				(font
					(size 1.27 1.27)
				)
				(justify left bottom)
				(hide yes)
			)
		)
		(pin "1"
		)
		(pin "2"
		)
		(instances
			(project "data-center-rdimm-ddr5-tester"
				(path ""
					(reference "C292")
					(unit 1)
				)
			)
		)
	)
	(symbol
		(lib_id "antmicroCapacitors0402:C_100n_0402")
		(at 325.12 86.36 180)
		(unit 1)
		(exclude_from_sim no)
		(in_bom yes)
		(on_board yes)
		(dnp no)
		(property "Reference" "C307"
			(at 318.77 85.09 0)
			(effects
				(font
					(size 1.27 1.27)
				)
			)
		)
		(property "Value" "C_100n_0402"
			(at 304.8 76.2 0)
			(effects
				(font
					(size 1.27 1.27)
					(thickness 0.15)
				)
				(justify left bottom)
				(hide yes)
			)
		)
		(property "Footprint" "antmicro-footprints:C_0402_1005Metric"
			(at 304.8 73.66 0)
			(effects
				(font
					(size 1.27 1.27)
					(thickness 0.15)
				)
				(justify left bottom)
				(hide yes)
			)
		)
		(property "Datasheet" "https://www.murata.com/products/productdetail?partno=GRM155R61H104KE14%23"
			(at 304.8 71.12 0)
			(effects
				(font
					(size 1.27 1.27)
					(thickness 0.15)
				)
				(justify left bottom)
				(hide yes)
			)
		)
		(property "Description" ""
			(at 325.12 86.36 0)
			(effects
				(font
					(size 1.27 1.27)
				)
				(hide yes)
			)
		)
		(property "Manufacturer" "Murata"
			(at 304.8 66.04 0)
			(effects
				(font
					(size 1.27 1.27)
					(thickness 0.15)
				)
				(justify left bottom)
				(hide yes)
			)
		)
		(property "MPN" "GRM155R61H104KE14D"
			(at 304.8 68.58 0)
			(effects
				(font
					(size 1.27 1.27)
					(thickness 0.15)
				)
				(justify left bottom)
				(hide yes)
			)
		)
		(property "Val" "100n"
			(at 318.77 87.63 0)
			(effects
				(font
					(size 1.27 1.27)
					(thickness 0.15)
				)
			)
		)
		(property "License" "Apache-2.0"
			(at 304.8 63.5 0)
			(effects
				(font
					(size 1.27 1.27)
					(thickness 0.15)
				)
				(justify left bottom)
				(hide yes)
			)
		)
		(property "Author" "Antmicro"
			(at 304.8 60.96 0)
			(effects
				(font
					(size 1.27 1.27)
					(thickness 0.15)
				)
				(justify left bottom)
				(hide yes)
			)
		)
		(property "Voltage" "50V"
			(at 304.8 58.42 0)
			(effects
				(font
					(size 1.27 1.27)
				)
				(justify left bottom)
				(hide yes)
			)
		)
		(property "Dielectric" "X5R"
			(at 304.8 55.88 0)
			(effects
				(font
					(size 1.27 1.27)
				)
				(justify left bottom)
				(hide yes)
			)
		)
		(pin "1"
		)
		(pin "2"
		)
		(instances
			(project "data-center-rdimm-ddr5-tester"
				(path ""
					(reference "C307")
					(unit 1)
				)
			)
		)
	)
	(symbol
		(lib_id "antmicropower:GND")
		(at 228.6 184.15 0)
		(mirror y)
		(unit 1)
		(exclude_from_sim no)
		(in_bom yes)
		(on_board yes)
		(dnp no)
		(property "Reference" "#PWR063"
			(at 219.71 186.69 0)
			(effects
				(font
					(size 1.27 1.27)
					(thickness 0.15)
				)
				(justify left bottom)
				(hide yes)
			)
		)
		(property "Value" "GND"
			(at 228.6 187.96 0)
			(effects
				(font
					(size 1.27 1.27)
					(thickness 0.15)
				)
			)
		)
		(property "Footprint" ""
			(at 219.71 191.77 0)
			(effects
				(font
					(size 1.27 1.27)
					(thickness 0.15)
				)
				(justify left bottom)
				(hide yes)
			)
		)
		(property "Datasheet" ""
			(at 219.71 196.85 0)
			(effects
				(font
					(size 1.27 1.27)
					(thickness 0.15)
				)
				(justify left bottom)
				(hide yes)
			)
		)
		(property "Description" ""
			(at 228.6 184.15 0)
			(effects
				(font
					(size 1.27 1.27)
				)
				(hide yes)
			)
		)
		(property "Author" "Antmicro"
			(at 219.71 191.77 0)
			(effects
				(font
					(size 1.27 1.27)
					(thickness 0.15)
				)
				(justify left bottom)
				(hide yes)
			)
		)
		(property "License" "Apache-2.0"
			(at 219.71 194.31 0)
			(effects
				(font
					(size 1.27 1.27)
					(thickness 0.15)
				)
				(justify left bottom)
				(hide yes)
			)
		)
		(pin "1"
		)
		(instances
			(project "data-center-rdimm-ddr5-tester"
				(path ""
					(reference "#PWR063")
					(unit 1)
				)
			)
		)
	)
	(symbol
		(lib_id "antmicroCapacitors0402:C_100n_0402")
		(at 325.12 54.61 0)
		(mirror y)
		(unit 1)
		(exclude_from_sim no)
		(in_bom yes)
		(on_board yes)
		(dnp no)
		(property "Reference" "C275"
			(at 318.77 53.34 0)
			(effects
				(font
					(size 1.27 1.27)
				)
			)
		)
		(property "Value" "C_100n_0402"
			(at 304.8 64.77 0)
			(effects
				(font
					(size 1.27 1.27)
					(thickness 0.15)
				)
				(justify left bottom)
				(hide yes)
			)
		)
		(property "Footprint" "antmicro-footprints:C_0402_1005Metric"
			(at 304.8 67.31 0)
			(effects
				(font
					(size 1.27 1.27)
					(thickness 0.15)
				)
				(justify left bottom)
				(hide yes)
			)
		)
		(property "Datasheet" "https://www.murata.com/products/productdetail?partno=GRM155R61H104KE14%23"
			(at 304.8 69.85 0)
			(effects
				(font
					(size 1.27 1.27)
					(thickness 0.15)
				)
				(justify left bottom)
				(hide yes)
			)
		)
		(property "Description" ""
			(at 325.12 54.61 0)
			(effects
				(font
					(size 1.27 1.27)
				)
				(hide yes)
			)
		)
		(property "Manufacturer" "Murata"
			(at 304.8 74.93 0)
			(effects
				(font
					(size 1.27 1.27)
					(thickness 0.15)
				)
				(justify left bottom)
				(hide yes)
			)
		)
		(property "MPN" "GRM155R61H104KE14D"
			(at 304.8 72.39 0)
			(effects
				(font
					(size 1.27 1.27)
					(thickness 0.15)
				)
				(justify left bottom)
				(hide yes)
			)
		)
		(property "Val" "100n"
			(at 318.77 55.88 0)
			(effects
				(font
					(size 1.27 1.27)
					(thickness 0.15)
				)
			)
		)
		(property "License" "Apache-2.0"
			(at 304.8 77.47 0)
			(effects
				(font
					(size 1.27 1.27)
					(thickness 0.15)
				)
				(justify left bottom)
				(hide yes)
			)
		)
		(property "Author" "Antmicro"
			(at 304.8 80.01 0)
			(effects
				(font
					(size 1.27 1.27)
					(thickness 0.15)
				)
				(justify left bottom)
				(hide yes)
			)
		)
		(property "Voltage" "50V"
			(at 304.8 82.55 0)
			(effects
				(font
					(size 1.27 1.27)
				)
				(justify left bottom)
				(hide yes)
			)
		)
		(property "Dielectric" "X5R"
			(at 304.8 85.09 0)
			(effects
				(font
					(size 1.27 1.27)
				)
				(justify left bottom)
				(hide yes)
			)
		)
		(pin "1"
		)
		(pin "2"
		)
		(instances
			(project "data-center-rdimm-ddr5-tester"
				(path ""
					(reference "C275")
					(unit 1)
				)
			)
		)
	)
	(symbol
		(lib_id "antmicroClockTimingClockGeneratorsPLLsFrequencySynthesizers:SI5319C-C-GM-ND")
		(at 311.15 181.61 0)
		(unit 1)
		(exclude_from_sim no)
		(in_bom yes)
		(on_board yes)
		(dnp no)
		(property "Reference" "U39"
			(at 330.2 175.26 0)
			(effects
				(font
					(size 1.27 1.27)
					(thickness 0.15)
				)
			)
		)
		(property "Value" "SI5319C-C-GM-ND"
			(at 346.71 189.23 0)
			(effects
				(font
					(size 1.27 1.27)
					(thickness 0.15)
				)
				(justify left bottom)
				(hide yes)
			)
		)
		(property "Footprint" "antmicro-footprints:QFN-36-1EP_6x6mm_P0.5mm_EP3.7x3.7mm"
			(at 346.71 191.77 0)
			(effects
				(font
					(size 1.27 1.27)
					(thickness 0.15)
				)
				(justify left bottom)
				(hide yes)
			)
		)
		(property "Datasheet" "https://www.skyworksinc.com/-/media/Skyworks/SL/documents/public/data-sheets/Si5319.pdf"
			(at 346.71 194.31 0)
			(effects
				(font
					(size 1.27 1.27)
					(thickness 0.15)
				)
				(justify left bottom)
				(hide yes)
			)
		)
		(property "Description" ""
			(at 311.15 181.61 0)
			(effects
				(font
					(size 1.27 1.27)
				)
				(hide yes)
			)
		)
		(property "MPN" "SI5319C-C-GM-ND"
			(at 322.58 177.8 0)
			(effects
				(font
					(size 1.27 1.27)
					(thickness 0.15)
				)
			)
		)
		(property "Manufacturer" "Skyworks Solutions"
			(at 346.71 196.85 0)
			(effects
				(font
					(size 1.27 1.27)
					(thickness 0.15)
				)
				(justify left bottom)
				(hide yes)
			)
		)
		(property "Author" "Antmicro"
			(at 346.71 199.39 0)
			(effects
				(font
					(size 1.27 1.27)
					(thickness 0.15)
				)
				(justify left bottom)
				(hide yes)
			)
		)
		(property "License" "Apache-2.0"
			(at 346.71 201.93 0)
			(effects
				(font
					(size 1.27 1.27)
					(thickness 0.15)
				)
				(justify left bottom)
				(hide yes)
			)
		)
		(pin "10"
		)
		(pin "3"
		)
		(pin "27"
		)
		(pin "1"
		)
		(pin "14"
		)
		(pin "5"
		)
		(pin "28"
		)
		(pin "29"
		)
		(pin "4"
		)
		(pin "23"
		)
		(pin "2"
		)
		(pin "35"
		)
		(pin "20"
		)
		(pin "26"
		)
		(pin "36"
		)
		(pin "12"
		)
		(pin "6"
		)
		(pin "9"
		)
		(pin "7"
		)
		(pin "8"
		)
		(pin "24"
		)
		(pin "31"
		)
		(pin "19"
		)
		(pin "25"
		)
		(pin "21"
		)
		(pin "32"
		)
		(pin "22"
		)
		(pin "11"
		)
		(pin "33"
		)
		(pin "13"
		)
		(pin "30"
		)
		(pin "34"
		)
		(pin "16"
		)
		(pin "18"
		)
		(pin "17"
		)
		(pin "15"
		)
		(pin "37"
		)
		(instances
			(project "data-center-rdimm-ddr5-tester"
				(path ""
					(reference "U39")
					(unit 1)
				)
			)
		)
	)
	(symbol
		(lib_id "antmicroCapacitors0402:C_100n_0402")
		(at 328.93 64.77 0)
		(mirror y)
		(unit 1)
		(exclude_from_sim no)
		(in_bom yes)
		(on_board yes)
		(dnp no)
		(property "Reference" "C290"
			(at 330.2 63.5 0)
			(effects
				(font
					(size 1.27 1.27)
				)
			)
		)
		(property "Value" "C_100n_0402"
			(at 308.61 74.93 0)
			(effects
				(font
					(size 1.27 1.27)
					(thickness 0.15)
				)
				(justify left bottom)
				(hide yes)
			)
		)
		(property "Footprint" "antmicro-footprints:C_0402_1005Metric"
			(at 308.61 77.47 0)
			(effects
				(font
					(size 1.27 1.27)
					(thickness 0.15)
				)
				(justify left bottom)
				(hide yes)
			)
		)
		(property "Datasheet" "https://www.murata.com/products/productdetail?partno=GRM155R61H104KE14%23"
			(at 308.61 80.01 0)
			(effects
				(font
					(size 1.27 1.27)
					(thickness 0.15)
				)
				(justify left bottom)
				(hide yes)
			)
		)
		(property "Description" ""
			(at 328.93 64.77 0)
			(effects
				(font
					(size 1.27 1.27)
				)
				(hide yes)
			)
		)
		(property "Manufacturer" "Murata"
			(at 308.61 85.09 0)
			(effects
				(font
					(size 1.27 1.27)
					(thickness 0.15)
				)
				(justify left bottom)
				(hide yes)
			)
		)
		(property "MPN" "GRM155R61H104KE14D"
			(at 308.61 82.55 0)
			(effects
				(font
					(size 1.27 1.27)
					(thickness 0.15)
				)
				(justify left bottom)
				(hide yes)
			)
		)
		(property "Val" "100n"
			(at 330.2 66.04 0)
			(effects
				(font
					(size 1.27 1.27)
					(thickness 0.15)
				)
			)
		)
		(property "License" "Apache-2.0"
			(at 308.61 87.63 0)
			(effects
				(font
					(size 1.27 1.27)
					(thickness 0.15)
				)
				(justify left bottom)
				(hide yes)
			)
		)
		(property "Author" "Antmicro"
			(at 308.61 90.17 0)
			(effects
				(font
					(size 1.27 1.27)
					(thickness 0.15)
				)
				(justify left bottom)
				(hide yes)
			)
		)
		(property "Voltage" "50V"
			(at 308.61 92.71 0)
			(effects
				(font
					(size 1.27 1.27)
				)
				(justify left bottom)
				(hide yes)
			)
		)
		(property "Dielectric" "X5R"
			(at 308.61 95.25 0)
			(effects
				(font
					(size 1.27 1.27)
				)
				(justify left bottom)
				(hide yes)
			)
		)
		(pin "1"
		)
		(pin "2"
		)
		(instances
			(project "data-center-rdimm-ddr5-tester"
				(path ""
					(reference "C290")
					(unit 1)
				)
			)
		)
	)
	(symbol
		(lib_id "antmicroCapacitors0402:C_100n_0402")
		(at 142.24 83.82 0)
		(mirror y)
		(unit 1)
		(exclude_from_sim no)
		(in_bom yes)
		(on_board yes)
		(dnp no)
		(property "Reference" "C253"
			(at 143.51 82.55 0)
			(effects
				(font
					(size 1.27 1.27)
				)
			)
		)
		(property "Value" "C_100n_0402"
			(at 121.92 93.98 0)
			(effects
				(font
					(size 1.27 1.27)
					(thickness 0.15)
				)
				(justify left bottom)
				(hide yes)
			)
		)
		(property "Footprint" "antmicro-footprints:C_0402_1005Metric"
			(at 121.92 96.52 0)
			(effects
				(font
					(size 1.27 1.27)
					(thickness 0.15)
				)
				(justify left bottom)
				(hide yes)
			)
		)
		(property "Datasheet" "https://www.murata.com/products/productdetail?partno=GRM155R61H104KE14%23"
			(at 121.92 99.06 0)
			(effects
				(font
					(size 1.27 1.27)
					(thickness 0.15)
				)
				(justify left bottom)
				(hide yes)
			)
		)
		(property "Description" ""
			(at 142.24 83.82 0)
			(effects
				(font
					(size 1.27 1.27)
				)
				(hide yes)
			)
		)
		(property "Manufacturer" "Murata"
			(at 121.92 104.14 0)
			(effects
				(font
					(size 1.27 1.27)
					(thickness 0.15)
				)
				(justify left bottom)
				(hide yes)
			)
		)
		(property "MPN" "GRM155R61H104KE14D"
			(at 121.92 101.6 0)
			(effects
				(font
					(size 1.27 1.27)
					(thickness 0.15)
				)
				(justify left bottom)
				(hide yes)
			)
		)
		(property "Val" "100n"
			(at 136.525 82.55 0)
			(effects
				(font
					(size 1.27 1.27)
					(thickness 0.15)
				)
			)
		)
		(property "License" "Apache-2.0"
			(at 121.92 106.68 0)
			(effects
				(font
					(size 1.27 1.27)
					(thickness 0.15)
				)
				(justify left bottom)
				(hide yes)
			)
		)
		(property "Author" "Antmicro"
			(at 121.92 109.22 0)
			(effects
				(font
					(size 1.27 1.27)
					(thickness 0.15)
				)
				(justify left bottom)
				(hide yes)
			)
		)
		(property "Voltage" "50V"
			(at 121.92 111.76 0)
			(effects
				(font
					(size 1.27 1.27)
				)
				(justify left bottom)
				(hide yes)
			)
		)
		(property "Dielectric" "X5R"
			(at 121.92 114.3 0)
			(effects
				(font
					(size 1.27 1.27)
				)
				(justify left bottom)
				(hide yes)
			)
		)
		(pin "1"
		)
		(pin "2"
		)
		(instances
			(project "data-center-rdimm-ddr5-tester"
				(path ""
					(reference "C253")
					(unit 1)
				)
			)
		)
	)
	(symbol
		(lib_id "antmicropower:GND")
		(at 300.99 241.3 0)
		(unit 1)
		(exclude_from_sim no)
		(in_bom yes)
		(on_board yes)
		(dnp no)
		(property "Reference" "#PWR0373"
			(at 309.88 243.84 0)
			(effects
				(font
					(size 1.27 1.27)
					(thickness 0.15)
				)
				(justify left bottom)
				(hide yes)
			)
		)
		(property "Value" "GND"
			(at 300.99 245.11 0)
			(effects
				(font
					(size 1.27 1.27)
					(thickness 0.15)
				)
			)
		)
		(property "Footprint" ""
			(at 309.88 248.92 0)
			(effects
				(font
					(size 1.27 1.27)
					(thickness 0.15)
				)
				(justify left bottom)
				(hide yes)
			)
		)
		(property "Datasheet" ""
			(at 309.88 254 0)
			(effects
				(font
					(size 1.27 1.27)
					(thickness 0.15)
				)
				(justify left bottom)
				(hide yes)
			)
		)
		(property "Description" ""
			(at 300.99 241.3 0)
			(effects
				(font
					(size 1.27 1.27)
				)
				(hide yes)
			)
		)
		(property "Author" "Antmicro"
			(at 309.88 248.92 0)
			(effects
				(font
					(size 1.27 1.27)
					(thickness 0.15)
				)
				(justify left bottom)
				(hide yes)
			)
		)
		(property "License" "Apache-2.0"
			(at 309.88 251.46 0)
			(effects
				(font
					(size 1.27 1.27)
					(thickness 0.15)
				)
				(justify left bottom)
				(hide yes)
			)
		)
		(pin "1"
		)
		(instances
			(project "data-center-rdimm-ddr5-tester"
				(path ""
					(reference "#PWR0373")
					(unit 1)
				)
			)
		)
	)
	(symbol
		(lib_id "antmicropower:GND")
		(at 295.91 191.77 0)
		(unit 1)
		(exclude_from_sim no)
		(in_bom yes)
		(on_board yes)
		(dnp no)
		(property "Reference" "#PWR0471"
			(at 304.8 194.31 0)
			(effects
				(font
					(size 1.27 1.27)
					(thickness 0.15)
				)
				(justify left bottom)
				(hide yes)
			)
		)
		(property "Value" "GND"
			(at 295.91 195.58 0)
			(effects
				(font
					(size 1.27 1.27)
					(thickness 0.15)
				)
			)
		)
		(property "Footprint" ""
			(at 304.8 199.39 0)
			(effects
				(font
					(size 1.27 1.27)
					(thickness 0.15)
				)
				(justify left bottom)
				(hide yes)
			)
		)
		(property "Datasheet" ""
			(at 304.8 204.47 0)
			(effects
				(font
					(size 1.27 1.27)
					(thickness 0.15)
				)
				(justify left bottom)
				(hide yes)
			)
		)
		(property "Description" ""
			(at 295.91 191.77 0)
			(effects
				(font
					(size 1.27 1.27)
				)
				(hide yes)
			)
		)
		(property "Author" "Antmicro"
			(at 304.8 199.39 0)
			(effects
				(font
					(size 1.27 1.27)
					(thickness 0.15)
				)
				(justify left bottom)
				(hide yes)
			)
		)
		(property "License" "Apache-2.0"
			(at 304.8 201.93 0)
			(effects
				(font
					(size 1.27 1.27)
					(thickness 0.15)
				)
				(justify left bottom)
				(hide yes)
			)
		)
		(pin "1"
		)
		(instances
			(project "data-center-rdimm-ddr5-tester"
				(path ""
					(reference "#PWR0471")
					(unit 1)
				)
			)
		)
	)
	(symbol
		(lib_id "antmicropower:GND")
		(at 238.76 184.15 0)
		(mirror y)
		(unit 1)
		(exclude_from_sim no)
		(in_bom yes)
		(on_board yes)
		(dnp no)
		(property "Reference" "#PWR0134"
			(at 229.87 186.69 0)
			(effects
				(font
					(size 1.27 1.27)
					(thickness 0.15)
				)
				(justify left bottom)
				(hide yes)
			)
		)
		(property "Value" "GND"
			(at 238.76 187.96 0)
			(effects
				(font
					(size 1.27 1.27)
					(thickness 0.15)
				)
			)
		)
		(property "Footprint" ""
			(at 229.87 191.77 0)
			(effects
				(font
					(size 1.27 1.27)
					(thickness 0.15)
				)
				(justify left bottom)
				(hide yes)
			)
		)
		(property "Datasheet" ""
			(at 229.87 196.85 0)
			(effects
				(font
					(size 1.27 1.27)
					(thickness 0.15)
				)
				(justify left bottom)
				(hide yes)
			)
		)
		(property "Description" ""
			(at 238.76 184.15 0)
			(effects
				(font
					(size 1.27 1.27)
				)
				(hide yes)
			)
		)
		(property "Author" "Antmicro"
			(at 229.87 191.77 0)
			(effects
				(font
					(size 1.27 1.27)
					(thickness 0.15)
				)
				(justify left bottom)
				(hide yes)
			)
		)
		(property "License" "Apache-2.0"
			(at 229.87 194.31 0)
			(effects
				(font
					(size 1.27 1.27)
					(thickness 0.15)
				)
				(justify left bottom)
				(hide yes)
			)
		)
		(pin "1"
		)
		(instances
			(project "data-center-rdimm-ddr5-tester"
				(path ""
					(reference "#PWR0134")
					(unit 1)
				)
			)
		)
	)
	(symbol
		(lib_id "antmicroCapacitors0402:C_100n_0402")
		(at 142.24 73.66 0)
		(mirror y)
		(unit 1)
		(exclude_from_sim no)
		(in_bom yes)
		(on_board yes)
		(dnp no)
		(property "Reference" "C251"
			(at 143.51 72.39 0)
			(effects
				(font
					(size 1.27 1.27)
				)
			)
		)
		(property "Value" "C_100n_0402"
			(at 121.92 83.82 0)
			(effects
				(font
					(size 1.27 1.27)
					(thickness 0.15)
				)
				(justify left bottom)
				(hide yes)
			)
		)
		(property "Footprint" "antmicro-footprints:C_0402_1005Metric"
			(at 121.92 86.36 0)
			(effects
				(font
					(size 1.27 1.27)
					(thickness 0.15)
				)
				(justify left bottom)
				(hide yes)
			)
		)
		(property "Datasheet" "https://www.murata.com/products/productdetail?partno=GRM155R61H104KE14%23"
			(at 121.92 88.9 0)
			(effects
				(font
					(size 1.27 1.27)
					(thickness 0.15)
				)
				(justify left bottom)
				(hide yes)
			)
		)
		(property "Description" ""
			(at 142.24 73.66 0)
			(effects
				(font
					(size 1.27 1.27)
				)
				(hide yes)
			)
		)
		(property "Manufacturer" "Murata"
			(at 121.92 93.98 0)
			(effects
				(font
					(size 1.27 1.27)
					(thickness 0.15)
				)
				(justify left bottom)
				(hide yes)
			)
		)
		(property "MPN" "GRM155R61H104KE14D"
			(at 121.92 91.44 0)
			(effects
				(font
					(size 1.27 1.27)
					(thickness 0.15)
				)
				(justify left bottom)
				(hide yes)
			)
		)
		(property "Val" "100n"
			(at 136.525 72.39 0)
			(effects
				(font
					(size 1.27 1.27)
					(thickness 0.15)
				)
			)
		)
		(property "License" "Apache-2.0"
			(at 121.92 96.52 0)
			(effects
				(font
					(size 1.27 1.27)
					(thickness 0.15)
				)
				(justify left bottom)
				(hide yes)
			)
		)
		(property "Author" "Antmicro"
			(at 121.92 99.06 0)
			(effects
				(font
					(size 1.27 1.27)
					(thickness 0.15)
				)
				(justify left bottom)
				(hide yes)
			)
		)
		(property "Voltage" "50V"
			(at 121.92 101.6 0)
			(effects
				(font
					(size 1.27 1.27)
				)
				(justify left bottom)
				(hide yes)
			)
		)
		(property "Dielectric" "X5R"
			(at 121.92 104.14 0)
			(effects
				(font
					(size 1.27 1.27)
				)
				(justify left bottom)
				(hide yes)
			)
		)
		(pin "1"
		)
		(pin "2"
		)
		(instances
			(project "data-center-rdimm-ddr5-tester"
				(path ""
					(reference "C251")
					(unit 1)
				)
			)
		)
	)
	(symbol
		(lib_id "antmicroCapacitors0402:C_100n_0402")
		(at 328.93 97.79 180)
		(unit 1)
		(exclude_from_sim no)
		(in_bom yes)
		(on_board yes)
		(dnp no)
		(property "Reference" "C304"
			(at 330.2 96.52 0)
			(effects
				(font
					(size 1.27 1.27)
				)
			)
		)
		(property "Value" "C_100n_0402"
			(at 308.61 87.63 0)
			(effects
				(font
					(size 1.27 1.27)
					(thickness 0.15)
				)
				(justify left bottom)
				(hide yes)
			)
		)
		(property "Footprint" "antmicro-footprints:C_0402_1005Metric"
			(at 308.61 85.09 0)
			(effects
				(font
					(size 1.27 1.27)
					(thickness 0.15)
				)
				(justify left bottom)
				(hide yes)
			)
		)
		(property "Datasheet" "https://www.murata.com/products/productdetail?partno=GRM155R61H104KE14%23"
			(at 308.61 82.55 0)
			(effects
				(font
					(size 1.27 1.27)
					(thickness 0.15)
				)
				(justify left bottom)
				(hide yes)
			)
		)
		(property "Description" ""
			(at 328.93 97.79 0)
			(effects
				(font
					(size 1.27 1.27)
				)
				(hide yes)
			)
		)
		(property "Manufacturer" "Murata"
			(at 308.61 77.47 0)
			(effects
				(font
					(size 1.27 1.27)
					(thickness 0.15)
				)
				(justify left bottom)
				(hide yes)
			)
		)
		(property "MPN" "GRM155R61H104KE14D"
			(at 308.61 80.01 0)
			(effects
				(font
					(size 1.27 1.27)
					(thickness 0.15)
				)
				(justify left bottom)
				(hide yes)
			)
		)
		(property "Val" "100n"
			(at 330.2 99.06 0)
			(effects
				(font
					(size 1.27 1.27)
					(thickness 0.15)
				)
			)
		)
		(property "License" "Apache-2.0"
			(at 308.61 74.93 0)
			(effects
				(font
					(size 1.27 1.27)
					(thickness 0.15)
				)
				(justify left bottom)
				(hide yes)
			)
		)
		(property "Author" "Antmicro"
			(at 308.61 72.39 0)
			(effects
				(font
					(size 1.27 1.27)
					(thickness 0.15)
				)
				(justify left bottom)
				(hide yes)
			)
		)
		(property "Voltage" "50V"
			(at 308.61 69.85 0)
			(effects
				(font
					(size 1.27 1.27)
				)
				(justify left bottom)
				(hide yes)
			)
		)
		(property "Dielectric" "X5R"
			(at 308.61 67.31 0)
			(effects
				(font
					(size 1.27 1.27)
				)
				(justify left bottom)
				(hide yes)
			)
		)
		(pin "1"
		)
		(pin "2"
		)
		(instances
			(project "data-center-rdimm-ddr5-tester"
				(path ""
					(reference "C304")
					(unit 1)
				)
			)
		)
	)
	(symbol
		(lib_id "antmicroResistors0402:R_4k7_0402")
		(at 300.99 180.34 90)
		(unit 1)
		(exclude_from_sim no)
		(in_bom yes)
		(on_board yes)
		(dnp no)
		(fields_autoplaced yes)
		(property "Reference" "R70"
			(at 303.53 176.53 90)
			(effects
				(font
					(size 1.27 1.27)
					(thickness 0.15)
				)
				(justify right)
			)
		)
		(property "Value" "R_4k7_0402"
			(at 313.69 160.02 0)
			(effects
				(font
					(size 1.27 1.27)
					(thickness 0.15)
				)
				(justify left bottom)
				(hide yes)
			)
		)
		(property "Footprint" "antmicro-footprints:R_0402_1005Metric"
			(at 316.23 160.02 0)
			(effects
				(font
					(size 1.27 1.27)
					(thickness 0.15)
				)
				(justify left bottom)
				(hide yes)
			)
		)
		(property "Datasheet" "https://www.bourns.com/docs/product-datasheets/cr.pdf"
			(at 318.77 160.02 0)
			(effects
				(font
					(size 1.27 1.27)
					(thickness 0.15)
				)
				(justify left bottom)
				(hide yes)
			)
		)
		(property "Description" ""
			(at 300.99 180.34 0)
			(effects
				(font
					(size 1.27 1.27)
				)
				(hide yes)
			)
		)
		(property "MPN" "CR0402-FX-4701GLF"
			(at 321.31 160.02 0)
			(effects
				(font
					(size 1.27 1.27)
					(thickness 0.15)
				)
				(justify left bottom)
				(hide yes)
			)
		)
		(property "Manufacturer" "Bourns"
			(at 323.85 160.02 0)
			(effects
				(font
					(size 1.27 1.27)
					(thickness 0.15)
				)
				(justify left bottom)
				(hide yes)
			)
		)
		(property "License" "Apache-2.0"
			(at 326.39 160.02 0)
			(effects
				(font
					(size 1.27 1.27)
					(thickness 0.15)
				)
				(justify left bottom)
				(hide yes)
			)
		)
		(property "Author" "Antmicro"
			(at 328.93 160.02 0)
			(effects
				(font
					(size 1.27 1.27)
					(thickness 0.15)
				)
				(justify left bottom)
				(hide yes)
			)
		)
		(property "Val" "4k7"
			(at 303.53 179.07 90)
			(effects
				(font
					(size 1.27 1.27)
					(thickness 0.15)
				)
				(justify right)
			)
		)
		(property "Tolerance" "1%"
			(at 311.15 160.02 0)
			(effects
				(font
					(size 1.27 1.27)
				)
				(justify left bottom)
				(hide yes)
			)
		)
		(pin "1"
		)
		(pin "2"
		)
		(instances
			(project "data-center-rdimm-ddr5-tester"
				(path ""
					(reference "R70")
					(unit 1)
				)
			)
		)
	)
	(symbol
		(lib_id "antmicroCapacitors0402:C_100n_0402")
		(at 274.32 204.47 0)
		(mirror x)
		(unit 1)
		(exclude_from_sim no)
		(in_bom yes)
		(on_board yes)
		(dnp no)
		(property "Reference" "C316"
			(at 273.05 205.74 0)
			(effects
				(font
					(size 1.27 1.27)
					(thickness 0.15)
				)
			)
		)
		(property "Value" "C_100n_0402"
			(at 294.64 194.31 0)
			(effects
				(font
					(size 1.27 1.27)
					(thickness 0.15)
				)
				(justify left bottom)
				(hide yes)
			)
		)
		(property "Footprint" "antmicro-footprints:C_0402_1005Metric"
			(at 294.64 191.77 0)
			(effects
				(font
					(size 1.27 1.27)
					(thickness 0.15)
				)
				(justify left bottom)
				(hide yes)
			)
		)
		(property "Datasheet" "https://www.murata.com/products/productdetail?partno=GRM155R61H104KE14%23"
			(at 294.64 189.23 0)
			(effects
				(font
					(size 1.27 1.27)
					(thickness 0.15)
				)
				(justify left bottom)
				(hide yes)
			)
		)
		(property "Description" ""
			(at 274.32 204.47 0)
			(effects
				(font
					(size 1.27 1.27)
				)
				(hide yes)
			)
		)
		(property "MPN" "GRM155R61H104KE14D"
			(at 294.64 186.69 0)
			(effects
				(font
					(size 1.27 1.27)
					(thickness 0.15)
				)
				(justify left bottom)
				(hide yes)
			)
		)
		(property "Manufacturer" "Murata"
			(at 294.64 184.15 0)
			(effects
				(font
					(size 1.27 1.27)
					(thickness 0.15)
				)
				(justify left bottom)
				(hide yes)
			)
		)
		(property "License" "Apache-2.0"
			(at 294.64 181.61 0)
			(effects
				(font
					(size 1.27 1.27)
					(thickness 0.15)
				)
				(justify left bottom)
				(hide yes)
			)
		)
		(property "Author" "Antmicro"
			(at 294.64 179.07 0)
			(effects
				(font
					(size 1.27 1.27)
					(thickness 0.15)
				)
				(justify left bottom)
				(hide yes)
			)
		)
		(property "Val" "100n"
			(at 280.67 205.74 0)
			(effects
				(font
					(size 1.27 1.27)
					(thickness 0.15)
				)
			)
		)
		(property "Voltage" "50V"
			(at 294.64 176.53 0)
			(effects
				(font
					(size 1.27 1.27)
				)
				(justify left bottom)
				(hide yes)
			)
		)
		(property "Dielectric" "X5R"
			(at 294.64 173.99 0)
			(effects
				(font
					(size 1.27 1.27)
				)
				(justify left bottom)
				(hide yes)
			)
		)
		(pin "1"
		)
		(pin "2"
		)
		(instances
			(project "data-center-rdimm-ddr5-tester"
				(path ""
					(reference "C316")
					(unit 1)
				)
			)
		)
	)
	(symbol
		(lib_id "antmicroResonators:Resonator_114.285MHZ_ABM8")
		(at 289.56 186.69 90)
		(mirror x)
		(unit 1)
		(exclude_from_sim no)
		(in_bom yes)
		(on_board yes)
		(dnp no)
		(fields_autoplaced yes)
		(property "Reference" "Y4"
			(at 285.75 189.23 90)
			(effects
				(font
					(size 1.27 1.27)
					(thickness 0.15)
				)
				(justify left)
			)
		)
		(property "Value" "Resonator_114.285MHZ_ABM8"
			(at 302.26 201.93 0)
			(effects
				(font
					(size 1.27 1.27)
					(thickness 0.15)
				)
				(justify left bottom)
				(hide yes)
			)
		)
		(property "Footprint" "antmicro-footprints:Resonator_SMD_Abracon_ABM8G_3.2x2.5mm"
			(at 304.8 201.93 0)
			(effects
				(font
					(size 1.27 1.27)
					(thickness 0.15)
				)
				(justify left bottom)
				(hide yes)
			)
		)
		(property "Datasheet" "https://abracon.com/Resonators/ABM8-166.pdf"
			(at 307.34 201.93 0)
			(effects
				(font
					(size 1.27 1.27)
					(thickness 0.15)
				)
				(justify left bottom)
				(hide yes)
			)
		)
		(property "Description" ""
			(at 289.56 186.69 0)
			(effects
				(font
					(size 1.27 1.27)
				)
				(hide yes)
			)
		)
		(property "MPN" "ABM8-166-114.285MHZ-T2"
			(at 283.845 190.5 0)
			(effects
				(font
					(size 1.27 1.27)
					(thickness 0.15)
				)
				(hide yes)
			)
		)
		(property "Manufacturer" "Abracon"
			(at 309.88 201.93 0)
			(effects
				(font
					(size 1.27 1.27)
					(thickness 0.15)
				)
				(justify left bottom)
				(hide yes)
			)
		)
		(property "Author" "Antmicro"
			(at 312.42 201.93 0)
			(effects
				(font
					(size 1.27 1.27)
					(thickness 0.15)
				)
				(justify left bottom)
				(hide yes)
			)
		)
		(property "License" "Apache-2.0"
			(at 314.96 201.93 0)
			(effects
				(font
					(size 1.27 1.27)
					(thickness 0.15)
				)
				(justify left bottom)
				(hide yes)
			)
		)
		(property "Val" "114.285 MHz"
			(at 285.75 191.77 90)
			(effects
				(font
					(size 1.27 1.27)
					(thickness 0.15)
				)
				(justify left)
			)
		)
		(pin "1"
		)
		(pin "2"
		)
		(pin "4"
		)
		(pin "3"
		)
		(instances
			(project "data-center-rdimm-ddr5-tester"
				(path ""
					(reference "Y4")
					(unit 1)
				)
			)
		)
	)
	(symbol
		(lib_name "XCAU25P-2FFVB676I_2")
		(lib_id "antmicroFPGAChips:XCAU25P-2FFVB676I")
		(at 76.2 154.94 0)
		(mirror y)
		(unit 10)
		(exclude_from_sim no)
		(in_bom yes)
		(on_board yes)
		(dnp no)
		(property "Reference" "U34"
			(at 68.58 144.145 0)
			(effects
				(font
					(size 1.27 1.27)
					(thickness 0.15)
				)
			)
		)
		(property "Value" "XCAU25P-2FFVB676I"
			(at 12.7 160.02 0)
			(effects
				(font
					(size 1.27 1.27)
					(thickness 0.15)
				)
				(justify left bottom)
				(hide yes)
			)
		)
		(property "Footprint" "antmicro-footprints:BGA-676_27x27mm_Layout26x26_P1x1mm_FFVB676"
			(at 12.7 162.56 0)
			(effects
				(font
					(size 1.27 1.27)
					(thickness 0.15)
				)
				(justify left bottom)
				(hide yes)
			)
		)
		(property "Datasheet" "https://docs.xilinx.com/viewer/book-attachment/2PXOpPtpaABIt0fkzeBLnw/hvbsEUaOT0OxFhln7VEVyA"
			(at 12.7 165.1 0)
			(effects
				(font
					(size 1.27 1.27)
					(thickness 0.15)
				)
				(justify left bottom)
				(hide yes)
			)
		)
		(property "Description" ""
			(at 76.2 154.94 0)
			(effects
				(font
					(size 1.27 1.27)
				)
				(hide yes)
			)
		)
		(property "MPN" "XCAU25P-2FFVB676I"
			(at 60.96 146.685 0)
			(effects
				(font
					(size 1.27 1.27)
					(thickness 0.15)
				)
			)
		)
		(property "Manufacturer" "AMD-Xilinx"
			(at 12.7 167.64 0)
			(effects
				(font
					(size 1.27 1.27)
					(thickness 0.15)
				)
				(justify left bottom)
				(hide yes)
			)
		)
		(property "Author" "Antmicro"
			(at 12.7 170.18 0)
			(effects
				(font
					(size 1.27 1.27)
					(thickness 0.15)
				)
				(justify left bottom)
				(hide yes)
			)
		)
		(property "License" "Apache-2.0"
			(at 12.7 172.72 0)
			(effects
				(font
					(size 1.27 1.27)
					(thickness 0.15)
				)
				(justify left bottom)
				(hide yes)
			)
		)
		(pin "AC23"
		)
		(pin "P20"
		)
		(pin "N19"
		)
		(pin "AA24"
		)
		(pin "J16"
		)
		(pin "J21"
		)
		(pin "AE10"
		)
		(pin "F6"
		)
		(pin "F7"
		)
		(pin "AF17"
		)
		(pin "AA15"
		)
		(pin "J25"
		)
		(pin "Y21"
		)
		(pin "AA7"
		)
		(pin "E26"
		)
		(pin "AD16"
		)
		(pin "V1"
		)
		(pin "AB14"
		)
		(pin "Y1"
		)
		(pin "E24"
		)
		(pin "AA14"
		)
		(pin "J20"
		)
		(pin "U25"
		)
		(pin "AE18"
		)
		(pin "U22"
		)
		(pin "P4"
		)
		(pin "P5"
		)
		(pin "R1"
		)
		(pin "R10"
		)
		(pin "P8"
		)
		(pin "P9"
		)
		(pin "R11"
		)
		(pin "R12"
		)
		(pin "AD3"
		)
		(pin "AD9"
		)
		(pin "AD4"
		)
		(pin "P18"
		)
		(pin "P3"
		)
		(pin "G14"
		)
		(pin "AE26"
		)
		(pin "B12"
		)
		(pin "AC2"
		)
		(pin "W7"
		)
		(pin "W8"
		)
		(pin "W11"
		)
		(pin "W17"
		)
		(pin "W2"
		)
		(pin "W22"
		)
		(pin "W3"
		)
		(pin "W6"
		)
		(pin "P6"
		)
		(pin "U26"
		)
		(pin "P19"
		)
		(pin "U1"
		)
		(pin "U10"
		)
		(pin "J15"
		)
		(pin "AB25"
		)
		(pin "L23"
		)
		(pin "P24"
		)
		(pin "G16"
		)
		(pin "C10"
		)
		(pin "F14"
		)
		(pin "U24"
		)
		(pin "Y24"
		)
		(pin "Y11"
		)
		(pin "J26"
		)
		(pin "AB4"
		)
		(pin "AD18"
		)
		(pin "J24"
		)
		(pin "AF2"
		)
		(pin "B26"
		)
		(pin "U6"
		)
		(pin "U7"
		)
		(pin "M11"
		)
		(pin "M12"
		)
		(pin "T20"
		)
		(pin "V23"
		)
		(pin "AD10"
		)
		(pin "D1"
		)
		(pin "AF1"
		)
		(pin "C8"
		)
		(pin "U13"
		)
		(pin "U14"
		)
		(pin "AD19"
		)
		(pin "Y4"
		)
		(pin "Y5"
		)
		(pin "E23"
		)
		(pin "C6"
		)
		(pin "AE14"
		)
		(pin "D22"
		)
		(pin "C20"
		)
		(pin "AB17"
		)
		(pin "AD24"
		)
		(pin "L1"
		)
		(pin "L10"
		)
		(pin "AE3"
		)
		(pin "G21"
		)
		(pin "AA17"
		)
		(pin "D6"
		)
		(pin "M25"
		)
		(pin "R17"
		)
		(pin "R18"
		)
		(pin "AE15"
		)
		(pin "H7"
		)
		(pin "H8"
		)
		(pin "R6"
		)
		(pin "R7"
		)
		(pin "AB20"
		)
		(pin "C5"
		)
		(pin "Y14"
		)
		(pin "AE13"
		)
		(pin "C13"
		)
		(pin "W4"
		)
		(pin "P22"
		)
		(pin "AF6"
		)
		(pin "B8"
		)
		(pin "AF18"
		)
		(pin "G22"
		)
		(pin "J2"
		)
		(pin "J3"
		)
		(pin "L3"
		)
		(pin "L6"
		)
		(pin "P12"
		)
		(pin "P15"
		)
		(pin "Y12"
		)
		(pin "K18"
		)
		(pin "V10"
		)
		(pin "V11"
		)
		(pin "D7"
		)
		(pin "D8"
		)
		(pin "P23"
		)
		(pin "AA3"
		)
		(pin "AB18"
		)
		(pin "H18"
		)
		(pin "B6"
		)
		(pin "R24"
		)
		(pin "R3"
		)
		(pin "P16"
		)
		(pin "P17"
		)
		(pin "AF23"
		)
		(pin "AC14"
		)
		(pin "M6"
		)
		(pin "B18"
		)
		(pin "M1"
		)
		(pin "B5"
		)
		(pin "D2"
		)
		(pin "G20"
		)
		(pin "M2"
		)
		(pin "B4"
		)
		(pin "AA16"
		)
		(pin "V9"
		)
		(pin "W1"
		)
		(pin "N5"
		)
		(pin "AA26"
		)
		(pin "B3"
		)
		(pin "D12"
		)
		(pin "N4"
		)
		(pin "AA2"
		)
		(pin "B23"
		)
		(pin "C12"
		)
		(pin "L5"
		)
		(pin "AA6"
		)
		(pin "B1"
		)
		(pin "H1"
		)
		(pin "A14"
		)
		(pin "A13"
		)
		(pin "AB2"
		)
		(pin "AE4"
		)
		(pin "Y16"
		)
		(pin "B24"
		)
		(pin "H16"
		)
		(pin "W24"
		)
		(pin "D18"
		)
		(pin "B20"
		)
		(pin "D21"
		)
		(pin "B19"
		)
		(pin "B25"
		)
		(pin "C24"
		)
		(pin "A15"
		)
		(pin "M26"
		)
		(pin "A23"
		)
		(pin "C17"
		)
		(pin "K21"
		)
		(pin "W23"
		)
		(pin "L24"
		)
		(pin "R20"
		)
		(pin "C21"
		)
		(pin "D24"
		)
		(pin "E15"
		)
		(pin "AD12"
		)
		(pin "D23"
		)
		(pin "D25"
		)
		(pin "C26"
		)
		(pin "B21"
		)
		(pin "Y26"
		)
		(pin "AE25"
		)
		(pin "C19"
		)
		(pin "C23"
		)
		(pin "P21"
		)
		(pin "A20"
		)
		(pin "L18"
		)
		(pin "A25"
		)
		(pin "K23"
		)
		(pin "V18"
		)
		(pin "C16"
		)
		(pin "V21"
		)
		(pin "E17"
		)
		(pin "A17"
		)
		(pin "P25"
		)
		(pin "AD25"
		)
		(pin "G18"
		)
		(pin "AB3"
		)
		(pin "J6"
		)
		(pin "J7"
		)
		(pin "K12"
		)
		(pin "K13"
		)
		(pin "AB16"
		)
		(pin "C1"
		)
		(pin "AF15"
		)
		(pin "J8"
		)
		(pin "K11"
		)
		(pin "AD1"
		)
		(pin "F25"
		)
		(pin "AE1"
		)
		(pin "V2"
		)
		(pin "U2"
		)
		(pin "U3"
		)
		(pin "F2"
		)
		(pin "V6"
		)
		(pin "P1"
		)
		(pin "L13"
		)
		(pin "L14"
		)
		(pin "AD5"
		)
		(pin "AE8"
		)
		(pin "AB10"
		)
		(pin "U15"
		)
		(pin "U16"
		)
		(pin "U17"
		)
		(pin "U18"
		)
		(pin "D26"
		)
		(pin "G5"
		)
		(pin "E25"
		)
		(pin "AD22"
		)
		(pin "A19"
		)
		(pin "P7"
		)
		(pin "Y2"
		)
		(pin "J22"
		)
		(pin "Y19"
		)
		(pin "Y3"
		)
		(pin "AB7"
		)
		(pin "AF22"
		)
		(pin "B2"
		)
		(pin "AA10"
		)
		(pin "V7"
		)
		(pin "V22"
		)
		(pin "J23"
		)
		(pin "AF12"
		)
		(pin "V16"
		)
		(pin "V17"
		)
		(pin "Y7"
		)
		(pin "D15"
		)
		(pin "H12"
		)
		(pin "AF7"
		)
		(pin "U23"
		)
		(pin "V19"
		)
		(pin "AF14"
		)
		(pin "AF13"
		)
		(pin "G8"
		)
		(pin "H20"
		)
		(pin "U11"
		)
		(pin "U12"
		)
		(pin "A5"
		)
		(pin "G6"
		)
		(pin "G7"
		)
		(pin "L15"
		)
		(pin "L16"
		)
		(pin "T8"
		)
		(pin "T9"
		)
		(pin "G19"
		)
		(pin "G17"
		)
		(pin "T4"
		)
		(pin "T5"
		)
		(pin "B13"
		)
		(pin "G23"
		)
		(pin "G3"
		)
		(pin "T26"
		)
		(pin "T3"
		)
		(pin "G13"
		)
		(pin "G2"
		)
		(pin "D17"
		)
		(pin "AD15"
		)
		(pin "Y8"
		)
		(pin "Y9"
		)
		(pin "AC24"
		)
		(pin "AD8"
		)
		(pin "F8"
		)
		(pin "G1"
		)
		(pin "AD6"
		)
		(pin "F18"
		)
		(pin "H17"
		)
		(pin "AA13"
		)
		(pin "K20"
		)
		(pin "AD7"
		)
		(pin "AA1"
		)
		(pin "AF19"
		)
		(pin "Y15"
		)
		(pin "AB13"
		)
		(pin "N13"
		)
		(pin "N14"
		)
		(pin "V14"
		)
		(pin "V15"
		)
		(pin "U8"
		)
		(pin "U9"
		)
		(pin "W13"
		)
		(pin "V5"
		)
		(pin "V8"
		)
		(pin "W5"
		)
		(pin "P26"
		)
		(pin "Y20"
		)
		(pin "L17"
		)
		(pin "L2"
		)
		(pin "H26"
		)
		(pin "Y6"
		)
		(pin "AC22"
		)
		(pin "D13"
		)
		(pin "V12"
		)
		(pin "V13"
		)
		(pin "AE9"
		)
		(pin "B7"
		)
		(pin "A11"
		)
		(pin "K9"
		)
		(pin "L11"
		)
		(pin "L12"
		)
		(pin "H5"
		)
		(pin "H6"
		)
		(pin "AE19"
		)
		(pin "C18"
		)
		(pin "H13"
		)
		(pin "AB23"
		)
		(pin "AC26"
		)
		(pin "R19"
		)
		(pin "R2"
		)
		(pin "H19"
		)
		(pin "AF20"
		)
		(pin "AF24"
		)
		(pin "B22"
		)
		(pin "B14"
		)
		(pin "D4"
		)
		(pin "AA18"
		)
		(pin "C22"
		)
		(pin "V24"
		)
		(pin "A12"
		)
		(pin "C7"
		)
		(pin "M7"
		)
		(pin "AB5"
		)
		(pin "W18"
		)
		(pin "T18"
		)
		(pin "T21"
		)
		(pin "F13"
		)
		(pin "D3"
		)
		(pin "F1"
		)
		(pin "L21"
		)
		(pin "L26"
		)
		(pin "AA11"
		)
		(pin "M20"
		)
		(pin "AC4"
		)
		(pin "AE5"
		)
		(pin "D19"
		)
		(pin "E10"
		)
		(pin "AA9"
		)
		(pin "Y22"
		)
		(pin "V3"
		)
		(pin "V4"
		)
		(pin "AD2"
		)
		(pin "AC10"
		)
		(pin "C25"
		)
		(pin "G4"
		)
		(pin "A6"
		)
		(pin "E6"
		)
		(pin "E7"
		)
		(pin "E1"
		)
		(pin "E19"
		)
		(pin "R4"
		)
		(pin "T10"
		)
		(pin "T11"
		)
		(pin "J10"
		)
		(pin "F17"
		)
		(pin "A24"
		)
		(pin "AC15"
		)
		(pin "C15"
		)
		(pin "A1"
		)
		(pin "J1"
		)
		(pin "J17"
		)
		(pin "AE6"
		)
		(pin "E4"
		)
		(pin "E5"
		)
		(pin "M23"
		)
		(pin "M3"
		)
		(pin "R22"
		)
		(pin "AA5"
		)
		(pin "AC12"
		)
		(pin "Y18"
		)
		(pin "W20"
		)
		(pin "AC21"
		)
		(pin "R23"
		)
		(pin "K10"
		)
		(pin "AC17"
		)
		(pin "AC20"
		)
		(pin "V20"
		)
		(pin "V25"
		)
		(pin "N1"
		)
		(pin "N10"
		)
		(pin "M4"
		)
		(pin "M5"
		)
		(pin "R25"
		)
		(pin "H3"
		)
		(pin "H4"
		)
		(pin "AD13"
		)
		(pin "AD17"
		)
		(pin "N26"
		)
		(pin "R13"
		)
		(pin "N6"
		)
		(pin "N7"
		)
		(pin "U4"
		)
		(pin "R5"
		)
		(pin "K3"
		)
		(pin "K4"
		)
		(pin "AF3"
		)
		(pin "J5"
		)
		(pin "P2"
		)
		(pin "N22"
		)
		(pin "T16"
		)
		(pin "T17"
		)
		(pin "C3"
		)
		(pin "AF4"
		)
		(pin "T13"
		)
		(pin "AA12"
		)
		(pin "AB26"
		)
		(pin "AF21"
		)
		(pin "N25"
		)
		(pin "N3"
		)
		(pin "N21"
		)
		(pin "J12"
		)
		(pin "A8"
		)
		(pin "W12"
		)
		(pin "H14"
		)
		(pin "U21"
		)
		(pin "W9"
		)
		(pin "T14"
		)
		(pin "AE23"
		)
		(pin "K19"
		)
		(pin "K24"
		)
		(pin "Y25"
		)
		(pin "G12"
		)
		(pin "N2"
		)
		(pin "N20"
		)
		(pin "T25"
		)
		(pin "AC8"
		)
		(pin "E16"
		)
		(pin "AC19"
		)
		(pin "C14"
		)
		(pin "F4"
		)
		(pin "F5"
		)
		(pin "U19"
		)
		(pin "AE12"
		)
		(pin "P14"
		)
		(pin "AF8"
		)
		(pin "AF9"
		)
		(pin "V26"
		)
		(pin "W19"
		)
		(pin "L4"
		)
		(pin "G24"
		)
		(pin "R15"
		)
		(pin "R16"
		)
		(pin "U5"
		)
		(pin "AC16"
		)
		(pin "AF25"
		)
		(pin "T7"
		)
		(pin "F24"
		)
		(pin "D16"
		)
		(pin "AA19"
		)
		(pin "D5"
		)
		(pin "L22"
		)
		(pin "B17"
		)
		(pin "H15"
		)
		(pin "AE21"
		)
		(pin "AE7"
		)
		(pin "K5"
		)
		(pin "K6"
		)
		(pin "T1"
		)
		(pin "AE22"
		)
		(pin "E22"
		)
		(pin "AF10"
		)
		(pin "AB6"
		)
		(pin "AD26"
		)
		(pin "AC13"
		)
		(pin "E18"
		)
		(pin "M15"
		)
		(pin "M16"
		)
		(pin "G15"
		)
		(pin "N8"
		)
		(pin "N9"
		)
		(pin "W26"
		)
		(pin "F20"
		)
		(pin "AD23"
		)
		(pin "AA8"
		)
		(pin "D20"
		)
		(pin "AF11"
		)
		(pin "E8"
		)
		(pin "F11"
		)
		(pin "AC5"
		)
		(pin "AA22"
		)
		(pin "E20"
		)
		(pin "W14"
		)
		(pin "M19"
		)
		(pin "H24"
		)
		(pin "K7"
		)
		(pin "K8"
		)
		(pin "C4"
		)
		(pin "H25"
		)
		(pin "W21"
		)
		(pin "P13"
		)
		(pin "L20"
		)
		(pin "AB21"
		)
		(pin "C2"
		)
		(pin "H22"
		)
		(pin "Y17"
		)
		(pin "AE11"
		)
		(pin "H2"
		)
		(pin "F23"
		)
		(pin "E11"
		)
		(pin "AB24"
		)
		(pin "AA4"
		)
		(pin "T6"
		)
		(pin "AD20"
		)
		(pin "A10"
		)
		(pin "C9"
		)
		(pin "W15"
		)
		(pin "E21"
		)
		(pin "AB22"
		)
		(pin "W16"
		)
		(pin "AC25"
		)
		(pin "T22"
		)
		(pin "K1"
		)
		(pin "AD14"
		)
		(pin "T2"
		)
		(pin "J19"
		)
		(pin "D9"
		)
		(pin "AE17"
		)
		(pin "AB1"
		)
		(pin "T24"
		)
		(pin "F9"
		)
		(pin "M8"
		)
		(pin "M9"
		)
		(pin "Y23"
		)
		(pin "AC7"
		)
		(pin "M13"
		)
		(pin "M14"
		)
		(pin "G25"
		)
		(pin "A9"
		)
		(pin "AB19"
		)
		(pin "A7"
		)
		(pin "N15"
		)
		(pin "N16"
		)
		(pin "Y13"
		)
		(pin "AF5"
		)
		(pin "R14"
		)
		(pin "AE20"
		)
		(pin "AB11"
		)
		(pin "W25"
		)
		(pin "T19"
		)
		(pin "H21"
		)
		(pin "K2"
		)
		(pin "T23"
		)
		(pin "AC6"
		)
		(pin "B15"
		)
		(pin "E9"
		)
		(pin "AC3"
		)
		(pin "F10"
		)
		(pin "A3"
		)
		(pin "F15"
		)
		(pin "U20"
		)
		(pin "G10"
		)
		(pin "N23"
		)
		(pin "AB15"
		)
		(pin "AA21"
		)
		(pin "P10"
		)
		(pin "P11"
		)
		(pin "J11"
		)
		(pin "Y10"
		)
		(pin "F19"
		)
		(pin "A22"
		)
		(pin "AE16"
		)
		(pin "F22"
		)
		(pin "G11"
		)
		(pin "K25"
		)
		(pin "B10"
		)
		(pin "AA20"
		)
		(pin "N24"
		)
		(pin "AA25"
		)
		(pin "E12"
		)
		(pin "D11"
		)
		(pin "E14"
		)
		(pin "AC1"
		)
		(pin "J4"
		)
		(pin "H11"
		)
		(pin "H9"
		)
		(pin "M22"
		)
		(pin "H10"
		)
		(pin "E13"
		)
		(pin "AD21"
		)
		(pin "D10"
		)
		(pin "B11"
		)
		(pin "G26"
		)
		(pin "L25"
		)
		(pin "AB9"
		)
		(pin "A2"
		)
		(pin "M21"
		)
		(pin "C11"
		)
		(pin "R21"
		)
		(pin "D14"
		)
		(pin "F12"
		)
		(pin "B9"
		)
		(pin "J9"
		)
		(pin "L19"
		)
		(pin "B16"
		)
		(pin "K22"
		)
		(pin "K26"
		)
		(pin "N11"
		)
		(pin "N12"
		)
		(pin "A16"
		)
		(pin "AB12"
		)
		(pin "L7"
		)
		(pin "L8"
		)
		(pin "AC11"
		)
		(pin "J18"
		)
		(pin "K16"
		)
		(pin "K17"
		)
		(pin "M24"
		)
		(pin "M17"
		)
		(pin "M18"
		)
		(pin "J14"
		)
		(pin "R8"
		)
		(pin "R9"
		)
		(pin "A26"
		)
		(pin "H23"
		)
		(pin "AF16"
		)
		(pin "F26"
		)
		(pin "F3"
		)
		(pin "AC18"
		)
		(pin "W10"
		)
		(pin "G9"
		)
		(pin "K14"
		)
		(pin "K15"
		)
		(pin "N17"
		)
		(pin "N18"
		)
		(pin "AC9"
		)
		(pin "J13"
		)
		(pin "AE24"
		)
		(pin "AA23"
		)
		(pin "E2"
		)
		(pin "E3"
		)
		(pin "AE2"
		)
		(pin "AF26"
		)
		(pin "A21"
		)
		(pin "L9"
		)
		(pin "M10"
		)
		(pin "F16"
		)
		(pin "F21"
		)
		(pin "R26"
		)
		(pin "T12"
		)
		(pin "T15"
		)
		(pin "AB8"
		)
		(pin "A18"
		)
		(pin "A4"
		)
		(pin "AD11"
		)
		(instances
			(project "data-center-rdimm-ddr5-tester"
				(path ""
					(reference "U34")
					(unit 10)
				)
			)
		)
	)
	(symbol
		(lib_id "antmicroCapacitors0402:C_100n_0402")
		(at 142.24 88.9 0)
		(mirror y)
		(unit 1)
		(exclude_from_sim no)
		(in_bom yes)
		(on_board yes)
		(dnp no)
		(property "Reference" "C254"
			(at 143.51 87.63 0)
			(effects
				(font
					(size 1.27 1.27)
				)
			)
		)
		(property "Value" "C_100n_0402"
			(at 121.92 99.06 0)
			(effects
				(font
					(size 1.27 1.27)
					(thickness 0.15)
				)
				(justify left bottom)
				(hide yes)
			)
		)
		(property "Footprint" "antmicro-footprints:C_0402_1005Metric"
			(at 121.92 101.6 0)
			(effects
				(font
					(size 1.27 1.27)
					(thickness 0.15)
				)
				(justify left bottom)
				(hide yes)
			)
		)
		(property "Datasheet" "https://www.murata.com/products/productdetail?partno=GRM155R61H104KE14%23"
			(at 121.92 104.14 0)
			(effects
				(font
					(size 1.27 1.27)
					(thickness 0.15)
				)
				(justify left bottom)
				(hide yes)
			)
		)
		(property "Description" ""
			(at 142.24 88.9 0)
			(effects
				(font
					(size 1.27 1.27)
				)
				(hide yes)
			)
		)
		(property "Manufacturer" "Murata"
			(at 121.92 109.22 0)
			(effects
				(font
					(size 1.27 1.27)
					(thickness 0.15)
				)
				(justify left bottom)
				(hide yes)
			)
		)
		(property "MPN" "GRM155R61H104KE14D"
			(at 121.92 106.68 0)
			(effects
				(font
					(size 1.27 1.27)
					(thickness 0.15)
				)
				(justify left bottom)
				(hide yes)
			)
		)
		(property "Val" "100n"
			(at 136.525 87.63 0)
			(effects
				(font
					(size 1.27 1.27)
					(thickness 0.15)
				)
			)
		)
		(property "License" "Apache-2.0"
			(at 121.92 111.76 0)
			(effects
				(font
					(size 1.27 1.27)
					(thickness 0.15)
				)
				(justify left bottom)
				(hide yes)
			)
		)
		(property "Author" "Antmicro"
			(at 121.92 114.3 0)
			(effects
				(font
					(size 1.27 1.27)
					(thickness 0.15)
				)
				(justify left bottom)
				(hide yes)
			)
		)
		(property "Voltage" "50V"
			(at 121.92 116.84 0)
			(effects
				(font
					(size 1.27 1.27)
				)
				(justify left bottom)
				(hide yes)
			)
		)
		(property "Dielectric" "X5R"
			(at 121.92 119.38 0)
			(effects
				(font
					(size 1.27 1.27)
				)
				(justify left bottom)
				(hide yes)
			)
		)
		(pin "1"
		)
		(pin "2"
		)
		(instances
			(project "data-center-rdimm-ddr5-tester"
				(path ""
					(reference "C254")
					(unit 1)
				)
			)
		)
	)
	(symbol
		(lib_id "antmicroCapacitors0402:C_100n_0402")
		(at 142.24 78.74 0)
		(mirror y)
		(unit 1)
		(exclude_from_sim no)
		(in_bom yes)
		(on_board yes)
		(dnp no)
		(property "Reference" "C252"
			(at 143.51 77.47 0)
			(effects
				(font
					(size 1.27 1.27)
				)
			)
		)
		(property "Value" "C_100n_0402"
			(at 121.92 88.9 0)
			(effects
				(font
					(size 1.27 1.27)
					(thickness 0.15)
				)
				(justify left bottom)
				(hide yes)
			)
		)
		(property "Footprint" "antmicro-footprints:C_0402_1005Metric"
			(at 121.92 91.44 0)
			(effects
				(font
					(size 1.27 1.27)
					(thickness 0.15)
				)
				(justify left bottom)
				(hide yes)
			)
		)
		(property "Datasheet" "https://www.murata.com/products/productdetail?partno=GRM155R61H104KE14%23"
			(at 121.92 93.98 0)
			(effects
				(font
					(size 1.27 1.27)
					(thickness 0.15)
				)
				(justify left bottom)
				(hide yes)
			)
		)
		(property "Description" ""
			(at 142.24 78.74 0)
			(effects
				(font
					(size 1.27 1.27)
				)
				(hide yes)
			)
		)
		(property "Manufacturer" "Murata"
			(at 121.92 99.06 0)
			(effects
				(font
					(size 1.27 1.27)
					(thickness 0.15)
				)
				(justify left bottom)
				(hide yes)
			)
		)
		(property "MPN" "GRM155R61H104KE14D"
			(at 121.92 96.52 0)
			(effects
				(font
					(size 1.27 1.27)
					(thickness 0.15)
				)
				(justify left bottom)
				(hide yes)
			)
		)
		(property "Val" "100n"
			(at 136.525 77.47 0)
			(effects
				(font
					(size 1.27 1.27)
					(thickness 0.15)
				)
			)
		)
		(property "License" "Apache-2.0"
			(at 121.92 101.6 0)
			(effects
				(font
					(size 1.27 1.27)
					(thickness 0.15)
				)
				(justify left bottom)
				(hide yes)
			)
		)
		(property "Author" "Antmicro"
			(at 121.92 104.14 0)
			(effects
				(font
					(size 1.27 1.27)
					(thickness 0.15)
				)
				(justify left bottom)
				(hide yes)
			)
		)
		(property "Voltage" "50V"
			(at 121.92 106.68 0)
			(effects
				(font
					(size 1.27 1.27)
				)
				(justify left bottom)
				(hide yes)
			)
		)
		(property "Dielectric" "X5R"
			(at 121.92 109.22 0)
			(effects
				(font
					(size 1.27 1.27)
				)
				(justify left bottom)
				(hide yes)
			)
		)
		(pin "1"
		)
		(pin "2"
		)
		(instances
			(project "data-center-rdimm-ddr5-tester"
				(path ""
					(reference "C252")
					(unit 1)
				)
			)
		)
	)
	(symbol
		(lib_id "antmicroCapacitors0402:C_100n_0402")
		(at 142.24 143.51 0)
		(mirror y)
		(unit 1)
		(exclude_from_sim no)
		(in_bom yes)
		(on_board yes)
		(dnp no)
		(property "Reference" "C229"
			(at 143.51 142.24 0)
			(effects
				(font
					(size 1.27 1.27)
				)
			)
		)
		(property "Value" "C_100n_0402"
			(at 121.92 153.67 0)
			(effects
				(font
					(size 1.27 1.27)
					(thickness 0.15)
				)
				(justify left bottom)
				(hide yes)
			)
		)
		(property "Footprint" "antmicro-footprints:C_0402_1005Metric"
			(at 121.92 156.21 0)
			(effects
				(font
					(size 1.27 1.27)
					(thickness 0.15)
				)
				(justify left bottom)
				(hide yes)
			)
		)
		(property "Datasheet" "https://www.murata.com/products/productdetail?partno=GRM155R61H104KE14%23"
			(at 121.92 158.75 0)
			(effects
				(font
					(size 1.27 1.27)
					(thickness 0.15)
				)
				(justify left bottom)
				(hide yes)
			)
		)
		(property "Description" ""
			(at 142.24 143.51 0)
			(effects
				(font
					(size 1.27 1.27)
				)
				(hide yes)
			)
		)
		(property "Manufacturer" "Murata"
			(at 121.92 163.83 0)
			(effects
				(font
					(size 1.27 1.27)
					(thickness 0.15)
				)
				(justify left bottom)
				(hide yes)
			)
		)
		(property "MPN" "GRM155R61H104KE14D"
			(at 121.92 161.29 0)
			(effects
				(font
					(size 1.27 1.27)
					(thickness 0.15)
				)
				(justify left bottom)
				(hide yes)
			)
		)
		(property "Val" "100n"
			(at 136.525 142.24 0)
			(effects
				(font
					(size 1.27 1.27)
					(thickness 0.15)
				)
			)
		)
		(property "License" "Apache-2.0"
			(at 121.92 166.37 0)
			(effects
				(font
					(size 1.27 1.27)
					(thickness 0.15)
				)
				(justify left bottom)
				(hide yes)
			)
		)
		(property "Author" "Antmicro"
			(at 121.92 168.91 0)
			(effects
				(font
					(size 1.27 1.27)
					(thickness 0.15)
				)
				(justify left bottom)
				(hide yes)
			)
		)
		(property "Voltage" "50V"
			(at 121.92 171.45 0)
			(effects
				(font
					(size 1.27 1.27)
				)
				(justify left bottom)
				(hide yes)
			)
		)
		(property "Dielectric" "X5R"
			(at 121.92 173.99 0)
			(effects
				(font
					(size 1.27 1.27)
				)
				(justify left bottom)
				(hide yes)
			)
		)
		(pin "1"
		)
		(pin "2"
		)
		(instances
			(project "data-center-rdimm-ddr5-tester"
				(path ""
					(reference "C229")
					(unit 1)
				)
			)
		)
	)
	(symbol
		(lib_id "antmicroCapacitors0402:C_100n_0402")
		(at 328.93 72.39 0)
		(mirror y)
		(unit 1)
		(exclude_from_sim no)
		(in_bom yes)
		(on_board yes)
		(dnp no)
		(property "Reference" "C293"
			(at 330.2 71.12 0)
			(effects
				(font
					(size 1.27 1.27)
				)
			)
		)
		(property "Value" "C_100n_0402"
			(at 308.61 82.55 0)
			(effects
				(font
					(size 1.27 1.27)
					(thickness 0.15)
				)
				(justify left bottom)
				(hide yes)
			)
		)
		(property "Footprint" "antmicro-footprints:C_0402_1005Metric"
			(at 308.61 85.09 0)
			(effects
				(font
					(size 1.27 1.27)
					(thickness 0.15)
				)
				(justify left bottom)
				(hide yes)
			)
		)
		(property "Datasheet" "https://www.murata.com/products/productdetail?partno=GRM155R61H104KE14%23"
			(at 308.61 87.63 0)
			(effects
				(font
					(size 1.27 1.27)
					(thickness 0.15)
				)
				(justify left bottom)
				(hide yes)
			)
		)
		(property "Description" ""
			(at 328.93 72.39 0)
			(effects
				(font
					(size 1.27 1.27)
				)
				(hide yes)
			)
		)
		(property "Manufacturer" "Murata"
			(at 308.61 92.71 0)
			(effects
				(font
					(size 1.27 1.27)
					(thickness 0.15)
				)
				(justify left bottom)
				(hide yes)
			)
		)
		(property "MPN" "GRM155R61H104KE14D"
			(at 308.61 90.17 0)
			(effects
				(font
					(size 1.27 1.27)
					(thickness 0.15)
				)
				(justify left bottom)
				(hide yes)
			)
		)
		(property "Val" "100n"
			(at 330.2 73.66 0)
			(effects
				(font
					(size 1.27 1.27)
					(thickness 0.15)
				)
			)
		)
		(property "License" "Apache-2.0"
			(at 308.61 95.25 0)
			(effects
				(font
					(size 1.27 1.27)
					(thickness 0.15)
				)
				(justify left bottom)
				(hide yes)
			)
		)
		(property "Author" "Antmicro"
			(at 308.61 97.79 0)
			(effects
				(font
					(size 1.27 1.27)
					(thickness 0.15)
				)
				(justify left bottom)
				(hide yes)
			)
		)
		(property "Voltage" "50V"
			(at 308.61 100.33 0)
			(effects
				(font
					(size 1.27 1.27)
				)
				(justify left bottom)
				(hide yes)
			)
		)
		(property "Dielectric" "X5R"
			(at 308.61 102.87 0)
			(effects
				(font
					(size 1.27 1.27)
				)
				(justify left bottom)
				(hide yes)
			)
		)
		(pin "1"
		)
		(pin "2"
		)
		(instances
			(project "data-center-rdimm-ddr5-tester"
				(path ""
					(reference "C293")
					(unit 1)
				)
			)
		)
	)
	(symbol
		(lib_id "antmicroCapacitors0402:C_100n_0402")
		(at 142.24 129.54 0)
		(mirror y)
		(unit 1)
		(exclude_from_sim no)
		(in_bom yes)
		(on_board yes)
		(dnp no)
		(property "Reference" "C231"
			(at 143.51 128.27 0)
			(effects
				(font
					(size 1.27 1.27)
				)
			)
		)
		(property "Value" "C_100n_0402"
			(at 121.92 139.7 0)
			(effects
				(font
					(size 1.27 1.27)
					(thickness 0.15)
				)
				(justify left bottom)
				(hide yes)
			)
		)
		(property "Footprint" "antmicro-footprints:C_0402_1005Metric"
			(at 121.92 142.24 0)
			(effects
				(font
					(size 1.27 1.27)
					(thickness 0.15)
				)
				(justify left bottom)
				(hide yes)
			)
		)
		(property "Datasheet" "https://www.murata.com/products/productdetail?partno=GRM155R61H104KE14%23"
			(at 121.92 144.78 0)
			(effects
				(font
					(size 1.27 1.27)
					(thickness 0.15)
				)
				(justify left bottom)
				(hide yes)
			)
		)
		(property "Description" ""
			(at 142.24 129.54 0)
			(effects
				(font
					(size 1.27 1.27)
				)
				(hide yes)
			)
		)
		(property "Manufacturer" "Murata"
			(at 121.92 149.86 0)
			(effects
				(font
					(size 1.27 1.27)
					(thickness 0.15)
				)
				(justify left bottom)
				(hide yes)
			)
		)
		(property "MPN" "GRM155R61H104KE14D"
			(at 121.92 147.32 0)
			(effects
				(font
					(size 1.27 1.27)
					(thickness 0.15)
				)
				(justify left bottom)
				(hide yes)
			)
		)
		(property "Val" "100n"
			(at 136.525 128.27 0)
			(effects
				(font
					(size 1.27 1.27)
					(thickness 0.15)
				)
			)
		)
		(property "License" "Apache-2.0"
			(at 121.92 152.4 0)
			(effects
				(font
					(size 1.27 1.27)
					(thickness 0.15)
				)
				(justify left bottom)
				(hide yes)
			)
		)
		(property "Author" "Antmicro"
			(at 121.92 154.94 0)
			(effects
				(font
					(size 1.27 1.27)
					(thickness 0.15)
				)
				(justify left bottom)
				(hide yes)
			)
		)
		(property "Voltage" "50V"
			(at 121.92 157.48 0)
			(effects
				(font
					(size 1.27 1.27)
				)
				(justify left bottom)
				(hide yes)
			)
		)
		(property "Dielectric" "X5R"
			(at 121.92 160.02 0)
			(effects
				(font
					(size 1.27 1.27)
				)
				(justify left bottom)
				(hide yes)
			)
		)
		(pin "1"
		)
		(pin "2"
		)
		(instances
			(project "data-center-rdimm-ddr5-tester"
				(path ""
					(reference "C231")
					(unit 1)
				)
			)
		)
	)
	(symbol
		(lib_id "antmicroResistors0402:R_4k7_0402")
		(at 300.99 238.76 270)
		(mirror x)
		(unit 1)
		(exclude_from_sim no)
		(in_bom yes)
		(on_board yes)
		(dnp no)
		(property "Reference" "R74"
			(at 298.45 234.95 90)
			(effects
				(font
					(size 1.27 1.27)
					(thickness 0.15)
				)
				(justify right)
			)
		)
		(property "Value" "R_4k7_0402"
			(at 288.29 218.44 0)
			(effects
				(font
					(size 1.27 1.27)
					(thickness 0.15)
				)
				(justify left bottom)
				(hide yes)
			)
		)
		(property "Footprint" "antmicro-footprints:R_0402_1005Metric"
			(at 285.75 218.44 0)
			(effects
				(font
					(size 1.27 1.27)
					(thickness 0.15)
				)
				(justify left bottom)
				(hide yes)
			)
		)
		(property "Datasheet" "https://www.bourns.com/docs/product-datasheets/cr.pdf"
			(at 283.21 218.44 0)
			(effects
				(font
					(size 1.27 1.27)
					(thickness 0.15)
				)
				(justify left bottom)
				(hide yes)
			)
		)
		(property "Description" ""
			(at 300.99 238.76 0)
			(effects
				(font
					(size 1.27 1.27)
				)
				(hide yes)
			)
		)
		(property "MPN" "CR0402-FX-4701GLF"
			(at 280.67 218.44 0)
			(effects
				(font
					(size 1.27 1.27)
					(thickness 0.15)
				)
				(justify left bottom)
				(hide yes)
			)
		)
		(property "Manufacturer" "Bourns"
			(at 278.13 218.44 0)
			(effects
				(font
					(size 1.27 1.27)
					(thickness 0.15)
				)
				(justify left bottom)
				(hide yes)
			)
		)
		(property "License" "Apache-2.0"
			(at 275.59 218.44 0)
			(effects
				(font
					(size 1.27 1.27)
					(thickness 0.15)
				)
				(justify left bottom)
				(hide yes)
			)
		)
		(property "Author" "Antmicro"
			(at 273.05 218.44 0)
			(effects
				(font
					(size 1.27 1.27)
					(thickness 0.15)
				)
				(justify left bottom)
				(hide yes)
			)
		)
		(property "Val" "4k7"
			(at 298.45 237.49 90)
			(effects
				(font
					(size 1.27 1.27)
					(thickness 0.15)
				)
				(justify right)
			)
		)
		(property "Tolerance" "1%"
			(at 290.83 218.44 0)
			(effects
				(font
					(size 1.27 1.27)
				)
				(justify left bottom)
				(hide yes)
			)
		)
		(pin "1"
		)
		(pin "2"
		)
		(instances
			(project "data-center-rdimm-ddr5-tester"
				(path ""
					(reference "R74")
					(unit 1)
				)
			)
		)
	)
	(symbol
		(lib_id "antmicroCapacitors0402:C_10u_10V_0402")
		(at 223.52 179.07 270)
		(mirror x)
		(unit 1)
		(exclude_from_sim no)
		(in_bom yes)
		(on_board yes)
		(dnp no)
		(property "Reference" "C288"
			(at 224.79 177.8 0)
			(effects
				(font
					(size 1.27 1.27)
					(thickness 0.15)
				)
				(justify right)
			)
		)
		(property "Value" "C_10u_10V_0402"
			(at 213.36 158.75 0)
			(effects
				(font
					(size 1.27 1.27)
					(thickness 0.15)
				)
				(justify left bottom)
				(hide yes)
			)
		)
		(property "Footprint" "antmicro-footprints:C_0402_1005Metric"
			(at 210.82 158.75 0)
			(effects
				(font
					(size 1.27 1.27)
					(thickness 0.15)
				)
				(justify left bottom)
				(hide yes)
			)
		)
		(property "Datasheet" "https://www.murata.com/products/productdetail?partno=GRM155R61A106ME11%23"
			(at 208.28 158.75 0)
			(effects
				(font
					(size 1.27 1.27)
					(thickness 0.15)
				)
				(justify left bottom)
				(hide yes)
			)
		)
		(property "Description" ""
			(at 223.52 179.07 0)
			(effects
				(font
					(size 1.27 1.27)
				)
				(hide yes)
			)
		)
		(property "MPN" "GRM155R61A106ME11D"
			(at 205.74 158.75 0)
			(effects
				(font
					(size 1.27 1.27)
					(thickness 0.15)
				)
				(justify left bottom)
				(hide yes)
			)
		)
		(property "Manufacturer" "Murata"
			(at 203.2 158.75 0)
			(effects
				(font
					(size 1.27 1.27)
					(thickness 0.15)
				)
				(justify left bottom)
				(hide yes)
			)
		)
		(property "License" "Apache-2.0"
			(at 200.66 158.75 0)
			(effects
				(font
					(size 1.27 1.27)
					(thickness 0.15)
				)
				(justify left bottom)
				(hide yes)
			)
		)
		(property "Author" "Antmicro"
			(at 198.12 158.75 0)
			(effects
				(font
					(size 1.27 1.27)
					(thickness 0.15)
				)
				(justify left bottom)
				(hide yes)
			)
		)
		(property "Val" "10u"
			(at 224.79 171.45 0)
			(effects
				(font
					(size 1.27 1.27)
					(thickness 0.15)
				)
				(justify right)
			)
		)
		(property "Voltage" "10V"
			(at 195.58 158.75 0)
			(effects
				(font
					(size 1.27 1.27)
				)
				(justify left bottom)
				(hide yes)
			)
		)
		(property "Dielectric" "X5R"
			(at 193.04 158.75 0)
			(effects
				(font
					(size 1.27 1.27)
				)
				(justify left bottom)
				(hide yes)
			)
		)
		(property "Public" ""
			(at 190.5 158.75 0)
			(effects
				(font
					(size 1.27 1.27)
				)
				(justify left bottom)
				(hide yes)
			)
		)
		(pin "1"
		)
		(pin "2"
		)
		(instances
			(project "data-center-rdimm-ddr5-tester"
				(path ""
					(reference "C288")
					(unit 1)
				)
			)
		)
	)
	(symbol
		(lib_id "antmicroCapacitors0402:C_100n_0402")
		(at 365.76 201.93 0)
		(mirror x)
		(unit 1)
		(exclude_from_sim no)
		(in_bom yes)
		(on_board yes)
		(dnp no)
		(property "Reference" "C308"
			(at 364.49 203.2 0)
			(effects
				(font
					(size 1.27 1.27)
				)
			)
		)
		(property "Value" "C_100n_0402"
			(at 386.08 191.77 0)
			(effects
				(font
					(size 1.27 1.27)
					(thickness 0.15)
				)
				(justify left bottom)
				(hide yes)
			)
		)
		(property "Footprint" "antmicro-footprints:C_0402_1005Metric"
			(at 386.08 189.23 0)
			(effects
				(font
					(size 1.27 1.27)
					(thickness 0.15)
				)
				(justify left bottom)
				(hide yes)
			)
		)
		(property "Datasheet" "https://www.murata.com/products/productdetail?partno=GRM155R61H104KE14%23"
			(at 386.08 186.69 0)
			(effects
				(font
					(size 1.27 1.27)
					(thickness 0.15)
				)
				(justify left bottom)
				(hide yes)
			)
		)
		(property "Description" ""
			(at 365.76 201.93 0)
			(effects
				(font
					(size 1.27 1.27)
				)
				(hide yes)
			)
		)
		(property "Manufacturer" "Murata"
			(at 386.08 181.61 0)
			(effects
				(font
					(size 1.27 1.27)
					(thickness 0.15)
				)
				(justify left bottom)
				(hide yes)
			)
		)
		(property "MPN" "GRM155R61H104KE14D"
			(at 386.08 184.15 0)
			(effects
				(font
					(size 1.27 1.27)
					(thickness 0.15)
				)
				(justify left bottom)
				(hide yes)
			)
		)
		(property "Val" "100n"
			(at 371.475 203.2 0)
			(effects
				(font
					(size 1.27 1.27)
					(thickness 0.15)
				)
			)
		)
		(property "License" "Apache-2.0"
			(at 386.08 179.07 0)
			(effects
				(font
					(size 1.27 1.27)
					(thickness 0.15)
				)
				(justify left bottom)
				(hide yes)
			)
		)
		(property "Author" "Antmicro"
			(at 386.08 176.53 0)
			(effects
				(font
					(size 1.27 1.27)
					(thickness 0.15)
				)
				(justify left bottom)
				(hide yes)
			)
		)
		(property "Voltage" "50V"
			(at 386.08 173.99 0)
			(effects
				(font
					(size 1.27 1.27)
				)
				(justify left bottom)
				(hide yes)
			)
		)
		(property "Dielectric" "X5R"
			(at 386.08 171.45 0)
			(effects
				(font
					(size 1.27 1.27)
				)
				(justify left bottom)
				(hide yes)
			)
		)
		(pin "1"
		)
		(pin "2"
		)
		(instances
			(project "data-center-rdimm-ddr5-tester"
				(path ""
					(reference "C308")
					(unit 1)
				)
			)
		)
	)
	(symbol
		(lib_id "antmicroCapacitors0402:C_100n_0402")
		(at 321.31 119.38 0)
		(mirror x)
		(unit 1)
		(exclude_from_sim no)
		(in_bom yes)
		(on_board yes)
		(dnp no)
		(property "Reference" "C289"
			(at 320.04 118.11 0)
			(effects
				(font
					(size 1.27 1.27)
				)
			)
		)
		(property "Value" "C_100n_0402"
			(at 341.63 109.22 0)
			(effects
				(font
					(size 1.27 1.27)
					(thickness 0.15)
				)
				(justify left bottom)
				(hide yes)
			)
		)
		(property "Footprint" "antmicro-footprints:C_0402_1005Metric"
			(at 341.63 106.68 0)
			(effects
				(font
					(size 1.27 1.27)
					(thickness 0.15)
				)
				(justify left bottom)
				(hide yes)
			)
		)
		(property "Datasheet" "https://www.murata.com/products/productdetail?partno=GRM155R61H104KE14%23"
			(at 341.63 104.14 0)
			(effects
				(font
					(size 1.27 1.27)
					(thickness 0.15)
				)
				(justify left bottom)
				(hide yes)
			)
		)
		(property "Description" ""
			(at 321.31 119.38 0)
			(effects
				(font
					(size 1.27 1.27)
				)
				(hide yes)
			)
		)
		(property "Manufacturer" "Murata"
			(at 341.63 99.06 0)
			(effects
				(font
					(size 1.27 1.27)
					(thickness 0.15)
				)
				(justify left bottom)
				(hide yes)
			)
		)
		(property "MPN" "GRM155R61H104KE14D"
			(at 341.63 101.6 0)
			(effects
				(font
					(size 1.27 1.27)
					(thickness 0.15)
				)
				(justify left bottom)
				(hide yes)
			)
		)
		(property "Val" "100n"
			(at 320.04 120.65 0)
			(effects
				(font
					(size 1.27 1.27)
					(thickness 0.15)
				)
			)
		)
		(property "License" "Apache-2.0"
			(at 341.63 96.52 0)
			(effects
				(font
					(size 1.27 1.27)
					(thickness 0.15)
				)
				(justify left bottom)
				(hide yes)
			)
		)
		(property "Author" "Antmicro"
			(at 341.63 93.98 0)
			(effects
				(font
					(size 1.27 1.27)
					(thickness 0.15)
				)
				(justify left bottom)
				(hide yes)
			)
		)
		(property "Voltage" "50V"
			(at 341.63 91.44 0)
			(effects
				(font
					(size 1.27 1.27)
				)
				(justify left bottom)
				(hide yes)
			)
		)
		(property "Dielectric" "X5R"
			(at 341.63 88.9 0)
			(effects
				(font
					(size 1.27 1.27)
				)
				(justify left bottom)
				(hide yes)
			)
		)
		(pin "1"
		)
		(pin "2"
		)
		(instances
			(project "data-center-rdimm-ddr5-tester"
				(path ""
					(reference "C289")
					(unit 1)
				)
			)
		)
	)
	(symbol
		(lib_id "antmicroCapacitors0402:C_100n_0402")
		(at 142.24 102.87 0)
		(mirror y)
		(unit 1)
		(exclude_from_sim no)
		(in_bom yes)
		(on_board yes)
		(dnp no)
		(property "Reference" "C256"
			(at 143.51 101.6 0)
			(effects
				(font
					(size 1.27 1.27)
				)
			)
		)
		(property "Value" "C_100n_0402"
			(at 121.92 113.03 0)
			(effects
				(font
					(size 1.27 1.27)
					(thickness 0.15)
				)
				(justify left bottom)
				(hide yes)
			)
		)
		(property "Footprint" "antmicro-footprints:C_0402_1005Metric"
			(at 121.92 115.57 0)
			(effects
				(font
					(size 1.27 1.27)
					(thickness 0.15)
				)
				(justify left bottom)
				(hide yes)
			)
		)
		(property "Datasheet" "https://www.murata.com/products/productdetail?partno=GRM155R61H104KE14%23"
			(at 121.92 118.11 0)
			(effects
				(font
					(size 1.27 1.27)
					(thickness 0.15)
				)
				(justify left bottom)
				(hide yes)
			)
		)
		(property "Description" ""
			(at 142.24 102.87 0)
			(effects
				(font
					(size 1.27 1.27)
				)
				(hide yes)
			)
		)
		(property "Manufacturer" "Murata"
			(at 121.92 123.19 0)
			(effects
				(font
					(size 1.27 1.27)
					(thickness 0.15)
				)
				(justify left bottom)
				(hide yes)
			)
		)
		(property "MPN" "GRM155R61H104KE14D"
			(at 121.92 120.65 0)
			(effects
				(font
					(size 1.27 1.27)
					(thickness 0.15)
				)
				(justify left bottom)
				(hide yes)
			)
		)
		(property "Val" "100n"
			(at 136.525 101.6 0)
			(effects
				(font
					(size 1.27 1.27)
					(thickness 0.15)
				)
			)
		)
		(property "License" "Apache-2.0"
			(at 121.92 125.73 0)
			(effects
				(font
					(size 1.27 1.27)
					(thickness 0.15)
				)
				(justify left bottom)
				(hide yes)
			)
		)
		(property "Author" "Antmicro"
			(at 121.92 128.27 0)
			(effects
				(font
					(size 1.27 1.27)
					(thickness 0.15)
				)
				(justify left bottom)
				(hide yes)
			)
		)
		(property "Voltage" "50V"
			(at 121.92 130.81 0)
			(effects
				(font
					(size 1.27 1.27)
				)
				(justify left bottom)
				(hide yes)
			)
		)
		(property "Dielectric" "X5R"
			(at 121.92 133.35 0)
			(effects
				(font
					(size 1.27 1.27)
				)
				(justify left bottom)
				(hide yes)
			)
		)
		(pin "1"
		)
		(pin "2"
		)
		(instances
			(project "data-center-rdimm-ddr5-tester"
				(path ""
					(reference "C256")
					(unit 1)
				)
			)
		)
	)
)
